FILE_TYPE = MULTI_PHYS_TABLE;

PART 'Q_CAPP'

{========================================================================================}
:VALUE    | VOLTAGE | TOLERANCE   | PACK_TYPE   | MATERIAL   | PART_NUMBER                  = STANDARD        | LIFECYCLE          | PART_NUMBER                  | JEDEC_TYPE                 | VALUE    | RATED_VOLTAGE | TOL         | CLASS      | DESCRIPTION                                            | COMPONENT_TYPE | LEAD_LENGTH | DFM_EXCLUSION | DAY        ;
{========================================================================================}
 '100UF'  | '25V'   | '20%'       | 'RDLLF'     | 'ALUM'     | 'TMP_QCC71004MZ65'(!)        = 'End of Design' | 'Comp-Release Qty' | 'CC71004MZ65'                |'EC71_248_304S'| '100UF'  | '25V'         | '20%'       | 'DISCRETE' | 'CAP ELEC 100U 25V(+-20%,105C,6.3*7.7)'                | 'SMT'          | ''          | ''            | ''        
 '100UF'  | '25V'   | '20%'       | 'RDLLF'     | 'EMPTY'    | 'TMP_QCC71004MZ65'(!)        = 'End of Design' | 'Comp-Release Qty' | 'CC71004MZ65'                |'EC71_248_304S'| '100UF'  | '25V'         | '20%'       | 'IO'       | 'CAP ELEC 100U 25V(+-20%,105C,6.3*7.7)'                | 'SMT'          | ''          | ''            | ''        
 '33UF'   | '8V'    | '20%'       | 'RDLLF'     | 'C_TAN'    | 'TMP_QCH6330MM682'(!)        = 'End of Design' | 'Comp-Approve'     | 'CH6330MM682'                |'TAJ_B2'| '33UF'   | '8V'          | '20%'       | 'DISCRETE' | 'CAP CHIP 33UF 8V +-20%,POSCAP(3528)'                  | 'SMT'          | ''          | ''            | ''        
 '33UF'   | '8V'    | '20%'       | 'RDLLF'     | 'EMPTY'    | 'TMP_QCH6330MM682'(!)        = 'End of Design' | 'Comp-Approve'     | 'CH6330MM682'                |'TAJ_B2'| '33UF'   | '8V'          | '20%'       | 'IO'       | 'CAP CHIP 33UF 8V +-20%,POSCAP(3528)'                  | 'SMT'          | ''          | ''            | ''        
 '4.7UF'  | '10V'   | '20%'       | 'RDLLF'     | 'C_TAN'    | 'TMP-C_S50_YAOHSUN_1213_1'(!) = ''              | ''                 | 'TMP-C_S50_YAOHSUN_1213_1'   |'TAJ_A'| '4.7UF'  | '10V'         | '20%'       | 'DISCRETE' | 'CAP CHIP 4.7U,10V(+-20%,TAN,3216)'                    | 'SMT'          | ''          | ''            | ''        
 '4.7UF'  | '10V'   | '20%'       | 'RDLLF'     | 'EMPTY'    | 'TMP-C_S50_YAOHSUN_1213_1'(!) = ''              | ''                 | 'TMP-C_S50_YAOHSUN_1213_1'   |'TAJ_A'| '4.7UF'  | '10V'         | '20%'       | 'IO'       | 'CAP CHIP 4.7U,10V(+-20%,TAN,3216)'                    | 'SMT'          | ''          | ''            | ''        
 '47UF'   | '25V'   | '20%'       | 'RDLLF'     | 'ALUM'     | 'TMP_QCC64704MZ59'(!)        = 'End of Design' | 'Comp-Approve'     | 'CC64704MZ59'                |'EC87_248_237S'| '47UF'   | '25V'         | '20%'       | 'DISCRETE' | 'CAP ELEC SMD 47U 25V(+-20%,105C,6.3*6.0)'             | 'SMT'          | ''          | ''            | ''        
 '47UF'   | '25V'   | '20%'       | 'RDLLF'     | 'EMPTY'    | 'TMP_QCC64704MZ59'(!)        = 'End of Design' | 'Comp-Approve'     | 'CC64704MZ59'                |'EC87_248_237S'| '47UF'   | '25V'         | '20%'       | 'IO'       | 'CAP ELEC SMD 47U 25V(+-20%,105C,6.3*6.0)'             | 'SMT'          | ''          | ''            | ''        
 '330UF'  | '2.5V'  | '20%'       | 'RDLLF'     | 'C_TAN'    | 'TMP_QCH733LM8821'(!)        = ''              | ''                 | 'CH733LM8821'                | 'TAJ_D'                    | '330UF'  | '2.5V'        | '20%'       | 'DISCRETE' | 'CAP CHIP 330UF 2.5V(+-20%,ESR=7,7343)'                | 'SMT'          | ''          | ''            | ''        
 '330UF'  | '2.5V'  | '20%'       | 'RDLLF'     | 'EMPTY'    | 'TMP_QCH733LM8821'(!)        = ''              | ''                 | 'CH733LM8821'                | 'TAJ_D'                    | '330UF'  | '2.5V'        | '20%'       | 'IO'       | 'CAP CHIP 330UF 2.5V(+-20%,ESR=7,7343)'                | 'SMT'          | ''          | ''            | ''        
 '820UF'  | '2.5V'  | '20%'       | 'RDLLF'     | 'OSCON'    | 'TMP_QCC7820JMD01'(!)        = ''              | ''                 | 'CC7820JMD01'                |'EC98_248_315'| '820UF'  | '2.5V'        | '20%'       | 'DISCRETE' | 'CAP OSCON DIP 820U 2.5V(+-20%,6.3*8)'                 | 'DIP'          | ''          | ''            | ''        
 '820UF'  | '2.5V'  | '20%'       | 'RDLLF'     | 'EMPTY'    | 'TMP_QCC7820JMD01'(!)        = ''              | ''                 | 'CC7820JMD01'                |'EC98_248_315'| '820UF'  | '2.5V'        | '20%'       | 'IO'       | 'CAP OSCON DIP 820U 2.5V(+-20%,6.3*8)'                 | 'DIP'          | ''          | ''            | ''        
 '560UF'  | '4V'    | '20%'       | 'RDLLF'     | 'OSCON'    | 'TMP_QCC7560IMD05'(!)        = 'End of Design' | 'P/N Release'      | 'CC7560IMD05'                |'EC98_248_315'| '560UF'  | '4V'          | '20%'       | 'DISCRETE' | 'CAP OSCON DIP 560U 4V(+-20%,6.3*8)'                   | 'DIP'          | ''          | ''            | ''        
 '560UF'  | '4V'    | '20%'       | 'RDLLF'     | 'EMPTY'    | 'TMP_QCC7560IMD05'(!)        = 'End of Design' | 'P/N Release'      | 'CC7560IMD05'                |'EC98_248_315'| '560UF'  | '4V'          | '20%'       | 'IO'       | 'CAP OSCON DIP 560U 4V(+-20%,6.3*8)'                   | 'DIP'          | ''          | ''            | ''        
 '470UF'  | '6.3V'  | '20%'       | 'RDLLF'     | 'OSCON'    | 'TMP_QCC74701MD03'(!)        = 'End of Design' | 'Comp-Approve'     | 'CC74701MD03'                |'EC98_248_315'| '470UF'  | '6.3V'        | '20%'       | 'DISCRETE' | 'CAP OSCON DIP 470U 6.3V(+-20%,6.3*8)'                 | 'DIP'          | ''          | ''            | ''        
 '470UF'  | '6.3V'  | '20%'       | 'RDLLF'     | 'EMPTY'    | 'TMP_QCC74701MD03'(!)        = 'End of Design' | 'Comp-Approve'     | 'CC74701MD03'                |'EC98_248_315'| '470UF'  | '6.3V'        | '20%'       | 'IO'       | 'CAP OSCON DIP 470U 6.3V(+-20%,6.3*8)'                 | 'DIP'          | ''          | ''            | ''        
 '560UF'  | '6.3V'  | '20%'       | 'RDLLF'     | 'OSCON'    | 'TMP_QCC75601MD01'(!)        = ''              | ''                 | 'CC75601MD01'                |'EC2-5_6-8_9-5'| '560UF'  | '6.3V'        | '20%'       | 'DISCRETE' | 'CAP OSCON DIP 560U 6.3V(+-20%,6.3*9)'                 | 'DIP'          | ''          | ''            | ''        
 '560UF'  | '6.3V'  | '20%'       | 'RDLLF'     | 'EMPTY'    | 'TMP_QCC75601MD01'(!)        = ''              | ''                 | 'CC75601MD01'                |'EC2-5_6-8_9-5'| '560UF'  | '6.3V'        | '20%'       | 'IO'       | 'CAP OSCON DIP 560U 6.3V(+-20%,6.3*9)'                 | 'DIP'          | ''          | ''            | ''        
 '220UF'  | '16V'   | '20%'       | 'RDLLF'     | 'ALUM'     | 'TMP_QCC72203MD01'(!)        = ''              | ''                 | 'CC72203MD01'                |'EC138_315_315'| '220UF'  | '16V'         | '20%'       | 'DISCRETE' | 'CAP ELEC DIP 220U 16V(+-20%,8*8)'                     | 'DIP'          | ''          | ''            | ''        
 '220UF'  | '16V'   | '20%'       | 'RDLLF'     | 'EMPTY'    | 'TMP_QCC72203MD01'(!)        = ''              | ''                 | 'CC72203MD01'                |'EC138_315_315'| '220UF'  | '16V'         | '20%'       | 'IO'       | 'CAP ELEC DIP 220U 16V(+-20%,8*8)'                     | 'DIP'          | ''          | ''            | ''        
 '330UF'  | '2.5V'  | '20%'       | 'RDLLF'     | 'ALUM'     | 'TMP_QCH733LM8812'(!)        = ''              | ''                 | 'CH733LM8812'                |'TAJ_D2E'| '330UF'  | '2.5V'        | '20%'       | 'DISCRETE' | 'CAP CHIP330U2.5V(20%,ESR9,7343,H1.8)EP'               | 'DIP'          | ''          | ''            | ''        
 '330UF'  | '2.5V'  | '20%'       | 'RDLLF'     | 'EMPTY'    | 'TMP_QCH733LM8812'(!)        = ''              | ''                 | 'CH733LM8812'                |'TAJ_D2E'| '330UF'  | '2.5V'        | '20%'       | 'IO'       | 'CAP CHIP330U2.5V(20%,ESR9,7343,H1.8)EP'               | 'DIP'          | ''          | ''            | ''        
 '270UF'  | '16V'   | '20%'       | 'RDLLF'     | 'OSCON'    | 'TMP_QCC72703MD03'(!)        = ''              | ''                 | 'CC72703MD03'                |'EC138_315_354A'| '270UF'  | '16V'         | '20%'       | 'DISCRETE' | 'CAP OSCON DIP 270U 16V(+-20%,8*9)'                    | 'DIP'          | ''          | ''            | ''        
 '270UF'  | '16V'   | '20%'       | 'RDLLF'     | 'EMPTY'    | 'TMP_QCC72703MD03'(!)        = ''              | ''                 | 'CC72703MD03'                |'EC138_315_354A'| '270UF'  | '16V'         | '20%'       | 'IO'       | 'CAP OSCON DIP 270U 16V(+-20%,8*9)'                    | 'DIP'          | ''          | ''            | ''        
 '270UF'  | '16V'   | '20%'       | 'RDLLF'     | 'ALUM'     | 'TMP_QCC72703MD36'(!)        = 'End of Design' | 'Comp-Approve'     | 'CC72703MD36'                |'EC138_315_512'| '270UF'  | '16V'         | '20%'       | 'DISCRETE' | 'CAP ELEC DIP 270U 16V(+-20%,8*12)EP'                  | 'DIP'          | ''          | ''            | ''        
 '270UF'  | '16V'   | '20%'       | 'RDLLF'     | 'EMPTY'    | 'TMP_QCC72703MD36'(!)        = 'End of Design' | 'Comp-Approve'     | 'CC72703MD36'                |'EC138_315_512'| '270UF'  | '16V'         | '20%'       | 'IO'       | 'CAP ELEC DIP 270U 16V(+-20%,8*12)EP'                  | 'DIP'          | ''          | ''            | ''        
 '220UF'  | '16V'   | '20%'       | 'RDLLF'     | 'ALUM'     | 'TMP_QCC72203MZ02'(!)        = 'End of Design' | 'Comp-Approve'     | 'CC72203MZ02'                |'EC178_394_304S'| '220UF'  | '16V'         | '20%'       | 'DISCRETE' | 'CAP ELEC SMD 220U 16V(20%,105C,10*8)'                 | 'SMD'          | ''          | ''            | ''        
 '220UF'  | '16V'   | '20%'       | 'RDLLF'     | 'EMPTY'    | 'TMP_QCC72203MZ02'(!)        = 'End of Design' | 'Comp-Approve'     | 'CC72203MZ02'                |'EC178_394_304S'| '220UF'  | '16V'         | '20%'       | 'IO'       | 'CAP ELEC SMD 220U 16V(20%,105C,10*8)'                 | 'SMD'          | ''          | ''            | ''        
 '100UF'  | '16V'   | '20%'       | 'RDLLF'     | 'OSCON'    | 'TMP_QCC71003MD02'(!)        = ''              | ''                 | 'CC71003MD02'                |'EC2-5_6-8_6'| '100UF'  | '16V'         | '20%'       | 'DISCRETE' | 'CAP OSCON DIP 100U 16V(20%,105C,6.3*6)'               | 'DIP'          | ''          | ''            | ''        
 '100UF'  | '16V'   | '20%'       | 'RDLLF'     | 'EMPTY'    | 'TMP_QCC71003MD02'(!)        = ''              | ''                 | 'CC71003MD02'                |'EC2-5_6-8_6'| '100UF'  | '16V'         | '20%'       | 'IO'       | 'CAP OSCON DIP 100U 16V(20%,105C,6.3*6)'               | 'DIP'          | ''          | ''            | ''        
 '100UF'  | '16V'   | '20%'       | 'RDLLF_SEL' | 'OSCON'    | 'CC71003MD02'(!)             = ''              | ''                 | 'CC71003MD02'                |'G_EC2-5_6-8_6'| '100UF'  | '16V'         | '20%'       | 'DISCRETE' | 'CAP OSCON DIP 100U 16V(20%,105C,6.3*6)'               | 'DIP'          | ''          | ''            | ''        
 '100UF'  | '16V'   | '20%'       | 'RDLLF_SEL' | 'EMPTY'    | 'CC71003MD02'(!)             = ''              | ''                 | 'CC71003MD02'                |'G_EC2-5_6-8_6'| '100UF'  | '16V'         | '20%'       | 'IO'       | 'CAP OSCON DIP 100U 16V(20%,105C,6.3*6)'               | 'DIP'          | ''          | ''            | ''        
 '330UF'  | '16V'   | '20%'       | 'RDLLF'     | 'ALUM'     | 'TMP_QCC73303MD18'(!)        = 'End of Design' | 'End of Life'      | 'CC73303MD18'                |'EC138_315_453_EOL'| '330UF'  | '16V'         | '20%'       | 'DISCRETE' | 'CAP ELEC DIP 330U 16V +-20% 105C 8*11.5'              | 'DIP'          | ''          | ''            | ''        
 '330UF'  | '16V'   | '20%'       | 'RDLLF'     | 'EMPTY'    | 'TMP_QCC73303MD18'(!)        = 'End of Design' | 'End of Life'      | 'CC73303MD18'                |'EC138_315_453_EOL'| '330UF'  | '16V'         | '20%'       | 'IO'       | 'CAP ELEC DIP 330U 16V +-20% 105C 8*11.5'              | 'DIP'          | ''          | ''            | ''        
 '220UF'  | '16V'   | '20%'       | 'RDLLF'     | 'ALUM'     | 'TMP_QCC72203MD38'(!)        = 'End of Design' | 'End of Life'      | 'CC72203MD38'                |'EC98_248_433_EOL'| '220UF'  | '16V'         | '20%'       | 'DISCRETE' | 'CAP ELEC DIP 220U 16V(20%,105C,6.3*11)'               | 'DIP'          | ''          | ''            | ''        
 '220UF'  | '16V'   | '20%'       | 'RDLLF'     | 'EMPTY'    | 'TMP_QCC72203MD38'(!)        = 'End of Design' | 'End of Life'      | 'CC72203MD38'                |'EC98_248_433_EOL'| '220UF'  | '16V'         | '20%'       | 'IO'       | 'CAP ELEC DIP 220U 16V(20%,105C,6.3*11)'               | 'DIP'          | ''          | ''            | ''        
 '470UF'  | '10V'   | '20%'       | 'RDLLF'     | 'ALUM'     | 'TMP_QCC74702MDC6'(!)        = ''              | ''                 | 'CC74702MDC6'                |'EC98_248_433'| '470UF'  | '10V'         | '20%'       | 'DISCRETE' | 'CAP ELEC DIP 470U 10V(20%,85C,6.3*11)'                | 'DIP'          | ''          | ''            | ''        
 '470UF'  | '10V'   | '20%'       | 'RDLLF'     | 'EMPTY'    | 'TMP_QCC74702MDC6'(!)        = ''              | ''                 | 'CC74702MDC6'                |'EC98_248_433'| '470UF'  | '10V'         | '20%'       | 'IO'       | 'CAP ELEC DIP 470U 10V(20%,85C,6.3*11)'                | 'DIP'          | ''          | ''            | ''        
 '1000UF' | '6.3V'  | '20%'       | 'RDLLF'     | 'ALUM'     | 'TMP_QCC81001MD00'(!)        = ''              | ''                 | 'CC81001MD00'                |'EC138_315_453'| '1000UF' | '6.3V'        | '20%'       | 'DISCRETE' | 'CAP ELEC 1000U 6.3V(20%,8*11.5)'                      | 'DIP'          | ''          | ''            | ''        
 '1000UF' | '6.3V'  | '20%'       | 'RDLLF'     | 'EMPTY'    | 'TMP_QCC81001MD00'(!)        = ''              | ''                 | 'CC81001MD00'                |'EC138_315_453'| '1000UF' | '6.3V'        | '20%'       | 'IO'       | 'CAP ELEC 1000U 6.3V(20%,8*11.5)'                      | 'DIP'          | ''          | ''            | ''        
 '47UF'   | '35V'   | '20%'       | 'RDLLF'     | 'ALUM'     | 'TMP_QCC64705MZ00'(!)        = ''              | ''                 | 'CC64705MZ00'                |'EC181_394_496S'| '47UF'   | '35V'         | '20%'       | 'DISCRETE' | 'CAP OSCON 47U 35V(20%,ESR30,10*12.6)SMD'              | 'SMD'          | ''          | ''            | ''        
 '47UF'   | '35V'   | '20%'       | 'RDLLF'     | 'EMPTY'    | 'TMP_QCC64705MZ00'(!)        = ''              | ''                 | 'CC64705MZ00'                |'EC181_394_496S'| '47UF'   | '35V'         | '20%'       | 'IO'       | 'CAP OSCON 47U 35V(20%,ESR30,10*12.6)SMD'              | 'SMD'          | ''          | ''            | ''        
 '560UF'  | '2.5V'  | '20%'       | 'RDLLF'     | 'ALUM'     | 'TMP-C_E07_KC_1112_1'(!)     = ''              | ''                 | 'TMP-C_E07_KC_1112_1'        |'EC78_197_315'| '560UF'  | '2.5V'        | '20%'       | 'DISCRETE' | 'CAP OSCON DIP 560U 2.5V(+-20%,5*8)'                   | 'DIP'          | ''          | ''            | ''        
 '560UF'  | '2.5V'  | '20%'       | 'RDLLF'     | 'EMPTY'    | 'TMP-C_E07_KC_1112_1'(!)     = ''              | ''                 | 'TMP-C_E07_KC_1112_1'        |'EC78_197_315'| '560UF'  | '2.5V'        | '20%'       | 'IO'       | 'CAP OSCON DIP 560U 2.5V(+-20%,5*8)'                   | 'DIP'          | ''          | ''            | ''        
 '330UF'  | '2V'    | '20%'       | 'RDLLF'     | 'C_TAN'    | 'TMP_QCH733RM8831'(!)        = ''              | ''                 | 'CH733RM8831'                | 'TAJ_DXA'                  | '330UF'  | '2V'          | '20%'       | 'DISCRETE' | 'CAP 330U 2V(20%,ESR=6,7343,H1.9)'                     | 'SMT'          | ''          | ''            | ''        
 '330UF'  | '2V'    | '20%'       | 'RDLLF'     | 'EMPTY'    | 'TMP_QCH733RM8831'(!)        = ''              | ''                 | 'CH733RM8831'                | 'TAJ_DXA'                  | '330UF'  | '2V'          | '20%'       | 'IO'       | 'CAP 330U 2V(20%,ESR=6,7343,H1.9)'                     | 'SMT'          | ''          | ''            | ''        
 '330UF'  | '6.3V'  | '20%'       | 'RDLLF'     | 'OSCON'    | 'TMP_QCC73301MZC1'(!)        = 'End of Design' | 'Comp-Approve'     | 'CC73301MZC1'                |'EC83_248_225S'| '330UF'  | '6.3V'        | '20%'       | 'DISCRETE' | 'CAP OSCON 330U 6.3V(20%,105C,6.3*5.9)SMD'             | 'SMT'          | ''          | ''            | ''        
 '330UF'  | '6.3V'  | '20%'       | 'RDLLF'     | 'EMPTY'    | 'TMP_QCC73301MZC1'(!)        = 'End of Design' | 'Comp-Approve'     | 'CC73301MZC1'                |'EC83_248_225S'| '330UF'  | '6.3V'        | '20%'       | 'IO'       | 'CAP OSCON 330U 6.3V(20%,105C,6.3*5.9)SMD'             | 'SMT'          | ''          | ''            | ''        
 '680UF'  | '2.5V'  | '20%'       | 'RDLLF'     | 'C_TAN'    | 'TMP_QCH768LM8801'(!)        = 'End of Design' | 'Comp-Approve'     | 'CH768LM8801'                |'TAJ_D3'| '680UF'  | '2.5V'        | '20%'       | 'DISCRETE' | 'CAP CHIP 680U 2.5V (20%,ESR6,7343,H2.8)'              | 'SMT'          | ''          | ''            | ''        
 '680UF'  | '2.5V'  | '20%'       | 'RDLLF'     | 'EMPTY'    | 'TMP_QCH768LM8801'(!)        = 'End of Design' | 'Comp-Approve'     | 'CH768LM8801'                |'TAJ_D3'| '680UF'  | '2.5V'        | '20%'       | 'IO'       | 'CAP CHIP 680U 2.5V (20%,ESR6,7343,H2.8)'              | 'SMT'          | ''          | ''            | ''        
 '180UF'  | '4V'    | '20%'       | 'RDLLF'     | 'C_TAN'    | 'TMP_QCH718KM8800'(!)        = 'End of Design' | 'Comp-Approve'     | 'CH718KM8800'                |'TAJ_UE'| '180UF'  | '4V'          | '20%'       | 'DISCRETE' | 'CAP CHIP 180UF 4V(20%,ESR0.012,7343)H4.2'             | 'SMT'          | ''          | ''            | ''        
 '180UF'  | '4V'    | '20%'       | 'RDLLF'     | 'EMPTY'    | 'TMP_QCH718KM8800'(!)        = 'End of Design' | 'Comp-Approve'     | 'CH718KM8800'                |'TAJ_UE'| '180UF'  | '4V'          | '20%'       | 'IO'       | 'CAP CHIP 180UF 4V(20%,ESR0.012,7343)H4.2'             | 'SMT'          | ''          | ''            | ''        
 '330UF'  | '6.3V'  | '20%'       | 'RDLLF'     | 'C_TAN'    | 'TMP_QCH7331MT800'(!)        = 'End of Design' | 'Comp-Approve'     | 'CH7331MT800'                |'TAJ_D3'| '330UF'  | '6.3V'        | '20%'       | 'DISCRETE' | 'CAP CHIP 330U,6.3V(20%,ESR9,TANT,7343)HF'             | 'DIP'          | ''          | ''            | ''        
 '330UF'  | '6.3V'  | '20%'       | 'RDLLF'     | 'EMPTY'    | 'TMP_QCH7331MT800'(!)        = 'End of Design' | 'Comp-Approve'     | 'CH7331MT800'                |'TAJ_D3'| '330UF'  | '6.3V'        | '20%'       | 'IO'       | 'CAP CHIP 330U,6.3V(20%,ESR9,TANT,7343)HF'             | 'DIP'          | ''          | ''            | ''        
 '560UF'  | '6.3V'  | '20%'       | 'RDLLF_SEL' | 'OSCON'    | 'CC75601MD05'(!)             = ''              | ''                 | 'CC75601MD05'                |'G_EC98_248_354'| '560UF'  | '6.3V'        | '20%'       | 'DISCRETE' | 'CAPOSCON DIP 560U6.3V(+-20%,6.3*9)SELASS'             | 'DIP'          | ''          | ''            | ''        
 '560UF'  | '6.3V'  | '20%'       | 'RDLLF_SEL' | 'EMPTY'    | 'CC75601MD05'(!)             = ''              | ''                 | 'CC75601MD05'                |'G_EC98_248_354'| '560UF'  | '6.3V'        | '20%'       | 'IO'       | 'CAPOSCON DIP 560U6.3V(+-20%,6.3*9)SELASS'             | 'DIP'          | ''          | ''            | ''        
 '270UF'  | '16V'   | '20%'       | 'RDLLF_SEL' | 'OSCON'    | 'CC72703MD12'(!)             = ''              | ''                 | 'CC72703MD12'                |'G_EC138_315_354A'| '270UF'  | '16V'         | '20%'       | 'DISCRETE' | 'CAP OSCON DIP 270U 16V(+-20%,8*9)SEL-ASS'             | 'DIP'          | ''          | ''            | ''        
 '270UF'  | '16V'   | '20%'       | 'RDLLF_SEL' | 'EMPTY'    | 'CC72703MD12'(!)             = ''              | ''                 | 'CC72703MD12'                |'G_EC138_315_354A'| '270UF'  | '16V'         | '20%'       | 'IO'       | 'CAP OSCON DIP 270U 16V(+-20%,8*9)SEL-ASS'             | 'DIP'          | ''          | ''            | ''        
 '150UF'  | '10V'   | '20%'       | 'RDLLF'     | 'C_TAN'    | 'CH7152MT829'(!)             = 'End of Design' | 'Comp-Approve'     | 'CH7152MT829'                |'TAJ_D'| '150UF'  | '10V'         | '20%'       | 'DISCRETE' | 'CAP CHIP 150U,10V(+-20%,TAN,7343)H2.8'                | 'SMT'          | ''          | ''            | ''        
 '150UF'  | '10V'   | '20%'       | 'RDLLF'     | 'EMPTY'    | 'CH7152MT829'(!)             = 'End of Design' | 'Comp-Approve'     | 'CH7152MT829'                |'TAJ_D'| '150UF'  | '10V'         | '20%'       | 'IO'       | 'CAP CHIP 150U,10V(+-20%,TAN,7343)H2.8'                | 'SMT'          | ''          | ''            | ''        
 '560UF'  | '2.5V'  | '20%'       | 'RDLLF_SEL' | 'OSCON'    | 'CC7560JMD03'(!)             = ''              | ''                 | 'CC7560JMD03'                |'G_EC78_197_355'| '560UF'  | '2.5V'        | '20%'       | 'DISCRETE' | 'CAP OSCON DIP 560U 2.5V(20%,105C,5*8)'                | 'DIP'          | ''          | ''            | ''        
 '560UF'  | '2.5V'  | '20%'       | 'RDLLF_SEL' | 'EMPTY'    | 'CC7560JMD03'(!)             = ''              | ''                 | 'CC7560JMD03'                |'G_EC78_197_355'| '560UF'  | '2.5V'        | '20%'       | 'IO'       | 'CAP OSCON DIP 560U 2.5V(20%,105C,5*8)'                | 'DIP'          | ''          | ''            | ''        
 '470UF'  | '2.5V'  | '20%'       | 'RDLLF'     | 'C_TAN'    | 'CH747LM8861'(!)             = 'End of Design' | 'Comp-Approve'     | 'CH747LM8861'                |'TAJ_D3L'| '470UF'  | '2.5V'        | '20%'       | 'DISCRETE' | 'CAP CHIP 470U 2.5V (20%,ESR6,7343,H2.8)'              | 'SMT'          | ''          | ''            | ''        
 '470UF'  | '2.5V'  | '20%'       | 'RDLLF'     | 'EMPTY'    | 'CH747LM8861'(!)             = 'End of Design' | 'Comp-Approve'     | 'CH747LM8861'                |'TAJ_D3L'| '470UF'  | '2.5V'        | '20%'       | 'IO'       | 'CAP CHIP 470U 2.5V (20%,ESR6,7343,H2.8)'              | 'SMT'          | ''          | ''            | ''        
 '22UF'   | '16V'   | '10%'       | 'RDLLF'     | 'C_TAN'    | 'CH6223KT600'(!)             = ''              | ''                 | 'CH6223KT600'                |'TAJ_B2'| '22UF'   | '16V'         | '10%'       | 'DISCRETE' | 'CAP CHIP 22UF 16V(+-10%,TAN,3528)H1.9'                | 'SMT'          | ''          | ''            | ''        
 '22UF'   | '16V'   | '10%'       | 'RDLLF'     | 'EMPTY'    | 'CH6223KT600'(!)             = ''              | ''                 | 'CH6223KT600'                |'TAJ_B2'| '22UF'   | '16V'         | '10%'       | 'IO'       | 'CAP CHIP 22UF 16V(+-10%,TAN,3528)H1.9'                | 'SMT'          | ''          | ''            | ''        
 '220UF'  | '10V'   | '20%'       | 'RDLLF'     | 'C_TAN'    | 'CH7222M8808'(!)             = 'End of Design' | 'Comp-Approve'     | 'CH7222M8808'                |'TAJ_D3'| '220UF'  | '10V'         | '20%'       | 'DISCRETE' | 'CAP CHIP 220U 10V(20%,ESR25,7343)H2.8'                | 'SMT'          | ''          | ''            | ''        
 '220UF'  | '10V'   | '20%'       | 'RDLLF'     | 'EMPTY'    | 'CH7222M8808'(!)             = 'End of Design' | 'Comp-Approve'     | 'CH7222M8808'                |'TAJ_D3'| '220UF'  | '10V'         | '20%'       | 'IO'       | 'CAP CHIP 220U 10V(20%,ESR25,7343)H2.8'                | 'SMT'          | ''          | ''            | ''        
 '68UF'   | '16V'   | '20%'       | 'RDLLF'     | 'C_POSCAP' | 'CH6683M8802'(!)             = 'End of Design' | 'Comp-Approve'     | 'CH6683M8802'                |'TAJ_D2'| '68UF'   | '16V'         | '20%'       | 'DISCRETE' | 'CAP CHIP 68U 16V( +-20%,ESR50,7343,H1.9)'             | 'SMT'          | ''          | ''            | '20100720'
 '68UF'   | '16V'   | '20%'       | 'RDLLF'     | 'EMPTY'    | 'CH6683M8802'(!)             = 'End of Design' | 'Comp-Approve'     | 'CH6683M8802'                |'TAJ_D2'| '68UF'   | '16V'         | '20%'       | 'IO'       | 'CAP CHIP 68U 16V( +-20%,ESR50,7343,H1.9)'             | 'SMT'          | ''          | ''            | '20100720'
 '470UF'  | '2.5V'  | '20%'       | 'RDLLF'     | 'C_TAN'    | 'CH747LM8807'(!)             = 'End of Design' | 'Comp-Approve'     | 'CH747LM8807'                |'TAJ_D2'| '470UF'  | '2.5V'        | '20%'       | 'DISCRETE' | 'CAP CHIP 470U 2.5V(+-20%,ESR6,7343,H1.9)'             | 'SMT'          | ''          | ''            | '20100924'
 '470UF'  | '2.5V'  | '20%'       | 'RDLLF'     | 'EMPTY'    | 'CH747LM8807'(!)             = 'End of Design' | 'Comp-Approve'     | 'CH747LM8807'                |'TAJ_D2'| '470UF'  | '2.5V'        | '20%'       | 'IO'       | 'CAP CHIP 470U 2.5V(+-20%,ESR6,7343,H1.9)'             | 'SMT'          | ''          | ''            | '20100924'
 '330UF'  | '2.5V'  | '20%'       | 'RDLLF'     | 'C_TAN'    | 'CH733LM8880'(!)             = ''              | ''                 | 'CH733LM8880'                | 'TAJ_D'                    | '330UF'  | '2.5V'        | '20%'       | 'DISCRETE' | 'CAP CHIP330UF2.5V(+-20%,ESR=6,7343,H2.8)'             | 'SMT'          | ''          | ''            | '20101004'
 '330UF'  | '2.5V'  | '20%'       | 'RDLLF'     | 'EMPTY'    | 'CH733LM8880'(!)             = ''              | ''                 | 'CH733LM8880'                | 'TAJ_D'                    | '330UF'  | '2.5V'        | '20%'       | 'IO'       | 'CAP CHIP330UF2.5V(+-20%,ESR=6,7343,H2.8)'             | 'SMT'          | ''          | ''            | '20101004'
 '470UF'  | '10V'   | '20%'       | 'RDLLF'     | 'C_TAN'    | 'CH7472MT801'(!)             = ''              | ''                 | 'CH7472MT801'                | 'TAJ_DA'                   | '470UF'  | '10V'         | '20%'       | 'DISCRETE' | 'CAP CHIP 470U 10V(20%,ESR=500M,7343)H4.1'             | 'SMT'          | ''          | ''            | '20101004'
 '470UF'  | '10V'   | '20%'       | 'RDLLF'     | 'EMPTY'    | 'CH7472MT801'(!)             = ''              | ''                 | 'CH7472MT801'                | 'TAJ_DA'                   | '470UF'  | '10V'         | '20%'       | 'IO'       | 'CAP CHIP 470U 10V(20%,ESR=500M,7343)H4.1'             | 'SMT'          | ''          | ''            | '20101004'
 '560UF'  | '6.3V'  | '20%'       | 'RDLLF'     | 'OSCON'    | 'CC75601MD02'(!)             = 'End of Design' | 'End of Life'      | 'CC75601MD02'                |'EC98_248_315_EOL'| '560UF'  | '6.3V'        | '20%'       | 'DISCRETE' | 'CAP OSCON DIP 560U 6.3V(+-20%,6.3*8)'                 | 'DIP'          | ''          | ''            | '20101005'
 '560UF'  | '6.3V'  | '20%'       | 'RDLLF'     | 'EMPTY'    | 'CC75601MD02'(!)             = 'End of Design' | 'End of Life'      | 'CC75601MD02'                |'EC98_248_315_EOL'| '560UF'  | '6.3V'        | '20%'       | 'IO'       | 'CAP OSCON DIP 560U 6.3V(+-20%,6.3*8)'                 | 'DIP'          | ''          | ''            | '20101005'
 '470UF'  | '2V'    | '20%'       | 'RDLLF'     | 'C_POSCAP' | 'CH747RM8811'(!)             = ''              | ''                 | 'CH747RM8811'                | 'TAJ_DXC'                  | '470UF'  | '2V'          | '20%'       | 'DISCRETE' | 'CAP CHIP 470U 2V(+-20% ESR=3,7343)H1.9'               | 'SMT'          | ''          | ''            | '20101116'
 '470UF'  | '2V'    | '20%'       | 'RDLLF'     | 'EMPTY'    | 'CH747RM8811'(!)             = ''              | ''                 | 'CH747RM8811'                | 'TAJ_DXC'                  | '470UF'  | '2V'          | '20%'       | 'IO'       | 'CAP CHIP 470U 2V(+-20% ESR=3,7343)H1.9'               | 'SMT'          | ''          | ''            | '20101116'
 '220UF'  | '2V'    | '20%'       | 'RDLLF_SEL' | 'C_TAN'    | 'CH722RM8809'(!)             = ''              | ''                 | 'CH722RM8809'                | 'TAJ_D2E'                  | '220UF'  | '2V'          | '20%'       | 'DISCRETE' | 'CAPCHIP220U2V(20%,ESR=6,H1.8,7343)SELASS'             | 'SMT'          | ''          | ''            | '20101116'
 '220UF'  | '2V'    | '20%'       | 'RDLLF_SEL' | 'EMPTY'    | 'CH722RM8809'(!)             = ''              | ''                 | 'CH722RM8809'                | 'TAJ_D2E'                  | '220UF'  | '2V'          | '20%'       | 'IO'       | 'CAPCHIP220U2V(20%,ESR=6,H1.8,7343)SELASS'             | 'SMT'          | ''          | ''            | '20101116'
 '270UF'  | '10V'   | '20%'       | 'RDLLF_SEL' | 'OSCON'    | 'TMP_T2B_KUOCHAN_1117_1'(!)  = ''              | ''                 | 'SP_TMP_T2B_KUOCHAN_1117_1'  |'G_EC138_315_276'| '270UF'  | '10V'         | '20%'       | 'DISCRETE' | 'CAP OSCON 270U 10V(20%,105C,8*7) SELASS'              | 'DIP'          | ''          | ''            | '20101118'
 '270UF'  | '10V'   | '20%'       | 'RDLLF_SEL' | 'EMPTY'    | 'TMP_T2B_KUOCHAN_1117_1'(!)  = ''              | ''                 | 'SP_TMP_T2B_KUOCHAN_1117_1'  |'G_EC138_315_276'| '270UF'  | '10V'         | '20%'       | 'IO'       | 'CAP OSCON 270U 10V(20%,105C,8*7) SELASS'              | 'DIP'          | ''          | ''            | '20101118'
 '220UF'  | '16V'   | '20%'       | 'RDLLF_SEL' | 'OSCON'    | 'TMP_T2B_KUOCHAN_1117_2'(!)  = ''              | ''                 | 'SP_TMP_T2B_KUOCHAN_1117_2'  |'G_EC138_315_276'| '220UF'  | '16V'         | '20%'       | 'DISCRETE' | 'CAP OSCON 220U 16V(20%,105C,8*7) SELASS'              | 'DIP'          | ''          | ''            | '20101118'
 '220UF'  | '16V'   | '20%'       | 'RDLLF_SEL' | 'EMPTY'    | 'TMP_T2B_KUOCHAN_1117_2'(!)  = ''              | ''                 | 'SP_TMP_T2B_KUOCHAN_1117_2'  |'G_EC138_315_276'| '220UF'  | '16V'         | '20%'       | 'IO'       | 'CAP OSCON 220U 16V(20%,105C,8*7) SELASS'              | 'DIP'          | ''          | ''            | '20101118'
 '560UF'  | '2.5V'  | '20%'       | 'RDLLF'     | 'OSCON'    | 'CC7560JMD03'(!)             = ''              | ''                 | 'CC7560JMD03'                |'EC78_197_355'| '560UF'  | '2.5V'        | '20%'       | 'DISCRETE' | 'CAP OSCON DIP 560U 2.5V(20%,105C,5*8)'                | 'DIP'          | ''          | ''            | '20110104'
 '560UF'  | '2.5V'  | '20%'       | 'RDLLF'     | 'EMPTY'    | 'CC7560JMD03'(!)             = ''              | ''                 | 'CC7560JMD03'                |'EC78_197_355'| '560UF'  | '2.5V'        | '20%'       | 'IO'       | 'CAP OSCON DIP 560U 2.5V(20%,105C,5*8)'                | 'DIP'          | ''          | ''            | '20110104'
 '330UF'  | '2V'    | '20%'       | 'RDLLF'     | 'C_TAN'    | 'CH733RM8602'(!)             = 'End of Design' | 'Comp-Approve'     | 'CH733RM8602'                |'TAJ_B2'| '330UF'  | '2V'          | '20%'       | 'DISCRETE' | 'CAPCHIP 330U 2V(20%,ESR13M,3528,H1.9)HF'              | 'SMT'          | ''          | ''            | '20110219'
 '330UF'  | '2V'    | '20%'       | 'RDLLF'     | 'EMPTY'    | 'CH733RM8602'(!)             = 'End of Design' | 'Comp-Approve'     | 'CH733RM8602'                |'TAJ_B2'| '330UF'  | '2V'          | '20%'       | 'IO'       | 'CAPCHIP 330U 2V(20%,ESR13M,3528,H1.9)HF'              | 'SMT'          | ''          | ''            | '20110219'
 '330UF'  | '2.5V'  | '20%'       | 'RDLLF'     | 'C_TAN'    | 'CH733LM8600'(!)             = ''              | ''                 | 'CH733LM8600'                |'TAJ_B2'| '330UF'  | '2.5V'        | '20%'       | 'DISCRETE' | 'CAP CHIP 330U 2.5V(+-20%,ESR35,3528)H1.9'             | 'SMT'          | ''          | ''            | '20110411'
 '330UF'  | '2.5V'  | '20%'       | 'RDLLF'     | 'EMPTY'    | 'CH733LM8600'(!)             = ''              | ''                 | 'CH733LM8600'                |'TAJ_B2'| '330UF'  | '2.5V'        | '20%'       | 'IO'       | 'CAP CHIP 330U 2.5V(+-20%,ESR35,3528)H1.9'             | 'SMT'          | ''          | ''            | '20110411'
 '330UF'  | '2.5V'  | '20%'       | 'RDLLF'     | 'C_TAN'    | 'CH733LM8605'(!)             = 'End of Design' | 'Comp-Approve'     | 'CH733LM8605'                |'TAJ_B2'| '330UF'  | '2.5V'        | '20%'       | 'DISCRETE' | 'CAP CHIP 330U 2.5V(+/-20%.ESR9.3528)H1.9'             | 'SMT'          | ''          | ''            | '20110503'
 '330UF'  | '2.5V'  | '20%'       | 'RDLLF'     | 'EMPTY'    | 'CH733LM8605'(!)             = 'End of Design' | 'Comp-Approve'     | 'CH733LM8605'                |'TAJ_B2'| '330UF'  | '2.5V'        | '20%'       | 'IO'       | 'CAP CHIP 330U 2.5V(+/-20%.ESR9.3528)H1.9'             | 'SMT'          | ''          | ''            | '20110503'
 '390UF'  | '2.5V'  | '20%'       | 'RDLLF'     | 'OSCON'    | 'CC7390JMD00'(!)             = ''              | ''                 | 'CC7390JMD00'                |'EC98_248_237'| '390U'   | '2.5V'        | '20%'       | 'DISCRETE' | 'CAP OSCON 390U 2.5V(20%,105C,6.3*6)ESR10'             | 'DIP'          | ''          | ''            | '20110516'
 '390UF'  | '2.5V'  | '20%'       | 'RDLLF'     | 'EMPTY'    | 'CC7390JMD00'(!)             = ''              | ''                 | 'CC7390JMD00'                |'EC98_248_237'| '390U'   | '2.5V'        | '20%'       | 'IO'       | 'CAP OSCON 390U 2.5V(20%,105C,6.3*6)ESR10'             | 'DIP'          | ''          | ''            | '20110516'
 '220UF'  | '10V'   | '20%'       | 'RDLLF'     | 'OSCON'    | 'CH7222MT804'(!)             = 'End of Design' | 'Comp-Approve'     | 'CH7222MT804'                |'TAJ_D'| '220UF'  | '10V'         | '20%'       | 'DISCRETE' | 'CAP CHIP 220U 10V(+-20%,TAN7343,H2.8)'                | 'SMT'          | ''          | ''            | '20110608'
 '220UF'  | '10V'   | '20%'       | 'RDLLF'     | 'EMPTY'    | 'CH7222MT804'(!)             = 'End of Design' | 'Comp-Approve'     | 'CH7222MT804'                |'TAJ_D'| '220UF'  | '10V'         | '20%'       | 'IO'       | 'CAP CHIP 220U 10V(+-20%,TAN7343,H2.8)'                | 'SMT'          | ''          | ''            | '20110608'
 '470UF'  | '16V'   | '20%'       | 'RDLLF'     | 'OSCON'    | 'CC74703MD05'(!)             = 'End of Design' | 'Comp-Approve'     | 'CC74703MD05'                |'EC197_394_512'| '220UF'  | '16V'         | '20%'       | 'DISCRETE' | 'CAP ELEC 470U 16V(20%,105C,ESR10,10*13)'              | 'DIP'          | ''          | ''            | '20110610'
 '470UF'  | '16V'   | '20%'       | 'RDLLF'     | 'EMPTY'    | 'CC74703MD05'(!)             = 'End of Design' | 'Comp-Approve'     | 'CC74703MD05'                |'EC197_394_512'| '220UF'  | '16V'         | '20%'       | 'IO'       | 'CAP ELEC 470U 16V(20%,105C,ESR10,10*13)'              | 'DIP'          | ''          | ''            | '20110610'
 '100UF'  | '16V'   | '20%'       | 'RDLLF'     | 'OSCON'    | 'CC71003MZ16'(!)             = ''              | ''                 | 'CC71003MZ16'                |'EC83_248_225S'| '100UF'  | '16V'         | '20%'       | 'DISCRETE' | 'CAP OSCON SMD 100U 16V(20%,105C,6.3*5.7)'             | 'SMT'          | ''          | ''            | '20110615'
 '100UF'  | '16V'   | '20%'       | 'RDLLF'     | 'EMPTY'    | 'CC71003MZ16'(!)             = ''              | ''                 | 'CC71003MZ16'                |'EC83_248_225S'| '100UF'  | '16V'         | '20%'       | 'IO'       | 'CAP OSCON SMD 100U 16V(20%,105C,6.3*5.7)'             | 'SMT'          | ''          | ''            | '20110615'
 '180UF'  | '16V'   | '20%'       | 'RDLLF'     | 'ALUM'     | 'CC71803MD01'(!)             = ''              | 'End of Life'      | 'CC71803MD01'                |'EC123_315_473S_EOL'| '180UF'  | '16V'         | '20%'       | 'DISCRETE' | 'CAP ELE SMD 180U 16V(+-20%105C,8*12)'                 | 'SMT'          | ''          | ''            | '20110824'
 '180UF'  | '16V'   | '20%'       | 'RDLLF'     | 'EMPTY'    | 'CC71803MD01'(!)             = ''              | 'End of Life'      | 'CC71803MD01'                |'EC123_315_473S_EOL'| '180UF'  | '16V'         | '20%'       | 'IO'       | 'CAP ELE SMD 180U 16V(+-20%105C,8*12)'                 | 'SMT'          | ''          | ''            | '20110824'
 '150UF'  | '16V'   | '20%'       | 'RDLLF'     | 'ALUM'     | 'CC71503MZ01'(!)             = 'End of Design' | 'Comp-Approve'     | 'CC71503MZ01'                |'EC123_315_304S'| '150UF'  | '16V'         | '20%'       | 'DISCRETE' | 'CAP ELEC SMD 150UF 16V(20%,105C,8*7.7)'               | 'SMT'          | ''          | ''            | '20110824'
 '150UF'  | '16V'   | '20%'       | 'RDLLF'     | 'EMPTY'    | 'CC71503MZ01'(!)             = 'End of Design' | 'Comp-Approve'     | 'CC71503MZ01'                |'EC123_315_304S'| '150UF'  | '16V'         | '20%'       | 'IO'       | 'CAP ELEC SMD 150UF 16V(20%,105C,8*7.7)'               | 'SMT'          | ''          | ''            | '20110824'
 '330UF'  | '6.3V'  | '20%'       | 'RDLLF'     | 'ALUM'     | 'CC73301MZ00'(!)             = ''              | ''                 | 'CC73301MZ00'                |'EC75_248_229SXA'| '330UF'  | '6.3V'        | '20%'       | 'DISCRETE' | 'CAP ELEC SMD 330U,6.3V(20%ESR17,6.3*5.8)'             | 'SMT'          | ''          | ''            | '20111226'
 '330UF'  | '6.3V'  | '20%'       | 'RDLLF'     | 'EMPTY'    | 'CC73301MZ00'(!)             = ''              | ''                 | 'CC73301MZ00'                |'EC75_248_229SXA'| '330UF'  | '6.3V'        | '20%'       | 'IO'       | 'CAP ELEC SMD 330U,6.3V(20%ESR17,6.3*5.8)'             | 'SMT'          | ''          | ''            | '20111226'
 '470UF'  | '10V'   | '20%'       | 'RDLLF'     | 'ALUM'     | 'CC74702MDA0'(!)             = 'End of Design' | 'Comp-Approve'     | 'CC74702MDA0'                |'EC98_248_433'| '470UF'  | '10V'         | '20%'       | 'DISCRETE' | 'CAP ELEC DIP 470U 10V(20%.105C.6*11)'                 | 'DIP'          | ''          | ''            | '20111226'
 '470UF'  | '10V'   | '20%'       | 'RDLLF'     | 'EMPTY'    | 'CC74702MDA0'(!)             = 'End of Design' | 'Comp-Approve'     | 'CC74702MDA0'                |'EC98_248_433'| '470UF'  | '10V'         | '20%'       | 'IO'       | 'CAP ELEC DIP 470U 10V(20%.105C.6*11)'                 | 'DIP'          | ''          | ''            | '20111226'
 '100UF'  | '100V'  | '20%'       | 'RDLLF'     | 'ALUM'     | 'CC71008MD01'(!)             = ''              | ''                 | 'CC71008MD01'                |'EC197_394_787'| '100UF'  | '100V'        | '20%'       | 'DISCRETE' | 'CAP ELEC DIP 100U 100V(20%.105C.10*20)'               | 'DIP'          | ''          | ''            | '20120110'
 '100UF'  | '100V'  | '20%'       | 'RDLLF'     | 'EMPTY'    | 'CC71008MD01'(!)             = ''              | ''                 | 'CC71008MD01'                |'EC197_394_787'| '100UF'  | '100V'        | '20%'       | 'IO'       | 'CAP ELEC DIP 100U 100V(20%.105C.10*20)'               | 'DIP'          | ''          | ''            | '20120110'
 '100UF'  | '100V'  | '20%'       | 'RDLLF_SEL' | 'ALUM'     | 'SP_CC71008MD01'(!)          = ''              | ''                 | 'CC71008MD01'                |'G_EC197_394_787'| '100UF'  | '100V'        | '20%'       | 'DISCRETE' | 'CAP ELEC DIP 100U 100V(20%.105C.10*20)'               | 'DIP'          | ''          | ''            | '20120110'
 '100UF'  | '100V'  | '20%'       | 'RDLLF_SEL' | 'EMPTY'    | 'SP_CC71008MD01'(!)          = ''              | ''                 | 'CC71008MD01'                |'G_EC197_394_787'| '100UF'  | '100V'        | '20%'       | 'IO'       | 'CAP ELEC DIP 100U 100V(20%.105C.10*20)'               | 'DIP'          | ''          | ''            | '20120110'
 '220UF'  | '100V'  | '20%'       | 'RDLLF'     | 'ALUM'     | 'CC72208MD00'(!)             = ''              | ''                 | 'CC72208MD00'                |'EC197_493_1240'| '220UF'  | '100V'        | '20%'       | 'DISCRETE' | 'CAP ELEC 220U 100V(20%,105C,12.5*31.5)'               | 'DIP'          | ''          | ''            | '20120116'
 '220UF'  | '100V'  | '20%'       | 'RDLLF'     | 'EMPTY'    | 'CC72208MD00'(!)             = ''              | ''                 | 'CC72208MD00'                |'EC197_493_1240'| '220UF'  | '100V'        | '20%'       | 'IO'       | 'CAP ELEC 220U 100V(20%,105C,12.5*31.5)'               | 'DIP'          | ''          | ''            | '20120116'
 '220UF'  | '100V'  | '20%'       | 'RDLLF_SEL' | 'ALUM'     | 'SP_CC72208MD00'(!)          = ''              | ''                 | 'CC72208MD00'                |'G_EC197_493_1240'| '220UF'  | '100V'        | '20%'       | 'DISCRETE' | 'CAP ELEC 220U 100V(20%,105C,12.5*31.5)'               | 'DIP'          | ''          | ''            | '20120116'
 '220UF'  | '100V'  | '20%'       | 'RDLLF_SEL' | 'EMPTY'    | 'SP_CC72208MD00'(!)          = ''              | ''                 | 'CC72208MD00'                |'G_EC197_493_1240'| '220UF'  | '100V'        | '20%'       | 'IO'       | 'CAP ELEC 220U 100V(20%,105C,12.5*31.5)'               | 'DIP'          | ''          | ''            | '20120116'
 '47UF'   | '100V'  | '20%'       | 'RDLLF_SEL' | 'ALUM'     | 'SP_TMP_S2L_JIACHENG_0213_1'(!) = ''              | ''                 | 'SP_TMP_S2L_JIACHENG_0213_1' |'G_EC197_394_492'| '47UF'   | '100V'        | '20%'       | 'DISCRETE' | 'CAP ELEC DIP 47U 100V(20%,10*12.5)SELASS'             | 'DIP'          | ''          | ''            | '20120213'
 '47UF'   | '100V'  | '20%'       | 'RDLLF_SEL' | 'EMPTY'    | 'SP_TMP_S2L_JIACHENG_0213_1'(!) = ''              | ''                 | 'SP_TMP_S2L_JIACHENG_0213_1' |'G_EC197_394_492'| '47UF'   | '100V'        | '20%'       | 'IO'       | 'CAP ELEC DIP 47U 100V(20%,10*12.5)SELASS'             | 'DIP'          | ''          | ''            | '20120213'
 '47UF'   | '100V'  | '20%'       | 'RDLLF'     | 'ALUM'     | 'CC64708MD01'(!)             = ''              | ''                 | 'CC64708MD01'                |'EC197_394_492'| '47UF'   | '100V'        | '20%'       | 'DISCRETE' | 'CAP ELEC DIP 47U 100V(20%,105C,10*12.5)'              | 'DIP'          | ''          | ''            | '20120221'
 '47UF'   | '100V'  | '20%'       | 'RDLLF'     | 'EMPTY'    | 'CC64708MD01'(!)             = ''              | ''                 | 'CC64708MD01'                |'EC197_394_492'| '47UF'   | '100V'        | '20%'       | 'IO'       | 'CAP ELEC DIP 47U 100V(20%,105C,10*12.5)'              | 'DIP'          | ''          | ''            | '20120221'
 '47UF'   | '100V'  | '20%'       | 'RDLLF_SEL' | 'ALUM'     | 'SP_CC64708MD01'(!)          = ''              | ''                 | 'CC64708MD01'                |'G_EC197_394_492'| '47UF'   | '100V'        | '20%'       | 'DISCRETE' | 'CAP ELEC DIP 47U 100V(20%,105C,10*12.5)'              | 'DIP'          | ''          | ''            | '20120221'
 '47UF'   | '100V'  | '20%'       | 'RDLLF_SEL' | 'EMPTY'    | 'SP_CC64708MD01'(!)          = ''              | ''                 | 'CC64708MD01'                |'G_EC197_394_492'| '47UF'   | '100V'        | '20%'       | 'IO'       | 'CAP ELEC DIP 47U 100V(20%,105C,10*12.5)'              | 'DIP'          | ''          | ''            | '20120221'
 '100U'   | '100V'  | '20%'       | 'RDLLF'     | 'ALUM'     | 'CC71008MD02'(!)             = ''              | ''                 | 'CC71008MD02'                |'EC197_394_787'| '100U'   | '100V'        | '20%'       | 'DISCRETE' | 'CAP ELEC DIP 100U 100V(20%,105C,10*20)'               | 'DIP'          | ''          | ''            | '20120221'
 '100U'   | '100V'  | '20%'       | 'RDLLF'     | 'EMPTY'    | 'CC71008MD02'(!)             = ''              | ''                 | 'CC71008MD02'                |'EC197_394_787'| '100U'   | '100V'        | '20%'       | 'IO'       | 'CAP ELEC DIP 100U 100V(20%,105C,10*20)'               | 'DIP'          | ''          | ''            | '20120221'
 '100U'   | '100V'  | '20%'       | 'RDLLF_SEL' | 'ALUM'     | 'SP_CC71008MD02'(!)          = ''              | ''                 | 'CC71008MD02'                |'G_EC197_394_787'| '100U'   | '100V'        | '20%'       | 'DISCRETE' | 'CAP ELEC DIP 100U 100V(20%,105C,10*20)'               | 'DIP'          | ''          | ''            | '20120221'
 '100U'   | '100V'  | '20%'       | 'RDLLF_SEL' | 'EMPTY'    | 'SP_CC71008MD02'(!)          = ''              | ''                 | 'CC71008MD02'                |'G_EC197_394_787'| '100U'   | '100V'        | '20%'       | 'IO'       | 'CAP ELEC DIP 100U 100V(20%,105C,10*20)'               | 'DIP'          | ''          | ''            | '20120221'
 '0.33F'  | '5.5V'  | '30%'       | 'RDLLF'     | 'ALUM'     | 'CCA3300TD00'(!)             = ''              | 'End of Life'      | 'CCA3300TD00'                |'EC453_P197_V_EOL'| '0.33F'  | '5.5V'        | '30%'       | 'DISCRETE' | 'CAP ELEC DIP 0.33F 5.5V(+-30%.10.5*11.5)'             | 'DIP'          | ''          | ''            | '20120308'
 '0.33F'  | '5.5V'  | '30%'       | 'RDLLF'     | 'EMPTY'    | 'CCA3300TD00'(!)             = ''              | 'End of Life'      | 'CCA3300TD00'                |'EC453_P197_V_EOL'| '0.33F'  | '5.5V'        | '30%'       | 'IO'       | 'CAP ELEC DIP 0.33F 5.5V(+-30%.10.5*11.5)'             | 'DIP'          | ''          | ''            | '20120308'
 '220UF'  | '6.3V'  | '20%'       | 'SMLF'      | 'OSCON'    | 'CC72201MZ12'(!)             = ''              | ''                 | 'CC72201MZ12'                |'EC56_197_229S'| '220UF'  | '6.3V'        | '20%'       | 'DISCRETE' | 'CAP OSCON 220U 6.3V(20%,105C,5*5.8)SMD'               | 'SMD'          | ''          | ''            | '20120308'
 '220UF'  | '6.3V'  | '20%'       | 'SMLF'      | 'EMPTY'    | 'CC72201MZ12'(!)             = ''              | ''                 | 'CC72201MZ12'                |'EC56_197_229S'| '220UF'  | '6.3V'        | '20%'       | 'IO'       | 'CAP OSCON 220U 6.3V(20%,105C,5*5.8)SMD'               | 'SMD'          | ''          | ''            | '20120308'
 '390UF'  | '2.5V'  | '20%'       | 'SMLF'      | 'OSCON'    | 'CC7390JMZ01'(!)             = ''              | ''                 | 'CC7390JMZ01'                |'EC56_197_229S'| '390UF'  | '2.5V'        | '20%'       | 'DISCRETE' | 'CAP OSCON 390U 2.5V(20%,105C,5*5.8)SMD'               | 'SMD'          | ''          | ''            | '20120308'
 '390UF'  | '2.5V'  | '20%'       | 'SMLF'      | 'EMPTY'    | 'CC7390JMZ01'(!)             = ''              | ''                 | 'CC7390JMZ01'                |'EC56_197_229S'| '390UF'  | '2.5V'        | '20%'       | 'IO'       | 'CAP OSCON 390U 2.5V(20%,105C,5*5.8)SMD'               | 'SMD'          | ''          | ''            | '20120308'
 '470UF'  | '2V'    | '20%'       | 'RDLLF'     | 'C_POSCAP' | 'CH747RM8800'(!)             = ''              | ''                 | 'CH747RM8800'                |'TAJ_D2'| '470UF'  | '2V'          | '20%'       | 'DISCRETE' | 'CAP CHIP 470U 2V(+-20%,ESR6,7343,H1.9)'               | 'SMT'          | ''          | ''            | '20120326'
 '470UF'  | '2V'    | '20%'       | 'RDLLF'     | 'EMPTY'    | 'CH747RM8800'(!)             = ''              | ''                 | 'CH747RM8800'                |'TAJ_D2'| '470UF'  | '2V'          | '20%'       | 'IO'       | 'CAP CHIP 470U 2V(+-20%,ESR6,7343,H1.9)'               | 'SMT'          | ''          | ''            | '20120326'
 '330UF'  | '2V'    | '35%'       | 'RDLLF'     | 'C_POSCAP' | 'CH733RY8802'(!)             = ''              | ''                 | 'CH733RY8802'                | 'TAJ_SX'                   | '330UF'  | '2V'          | '35%'       | 'DISCRETE' | 'CAP CHIP 330U 2V(+10/-35%,7343,LES=9)'                | 'SMT'          | ''          | ''            | '20120326'
 '330UF'  | '2V'    | '35%'       | 'RDLLF'     | 'EMPTY'    | 'CH733RY8802'(!)             = ''              | ''                 | 'CH733RY8802'                | 'TAJ_SX'                   | '330UF'  | '2V'          | '35%'       | 'IO'       | 'CAP CHIP 330U 2V(+10/-35%,7343,LES=9)'                | 'SMT'          | ''          | ''            | '20120326'
 '470UF'  | '2V'    | '35%'       | 'RDLLF'     | 'C_POSCAP' | 'CH747RY8800'(!)             = ''              | ''                 | 'CH747RY8800'                | 'TAJ_D'                    | '470UF'  | '2V'          | '35%'       | 'DISCRETE' | 'CAP CHIP 470U 2V(+10/-35%.ESR=9.7343)'                | 'SMT'          | ''          | ''            | '20120326'
 '470UF'  | '2V'    | '35%'       | 'RDLLF'     | 'EMPTY'    | 'CH747RY8800'(!)             = ''              | ''                 | 'CH747RY8800'                | 'TAJ_D'                    | '470UF'  | '2V'          | '35%'       | 'IO'       | 'CAP CHIP 470U 2V(+10/-35%.ESR=9.7343)'                | 'SMT'          | ''          | ''            | '20120326'
 '470UF'  | '2V'    | '20%'       | 'RDLLF'     | 'C_POSCAP' | 'CH747RM8802'(!)             = ''              | ''                 | 'CH747RM8802'                |'TAJ_SX'| '470UF'  | '2V'          | '20%'       | 'DISCRETE' | 'CAP CHIP 470U 2V(+-20%,ESR9,7343,H1.9)'               | 'SMT'          | ''          | ''            | '20120326'
 '470UF'  | '2V'    | '20%'       | 'RDLLF'     | 'EMPTY'    | 'CH747RM8802'(!)             = ''              | ''                 | 'CH747RM8802'                |'TAJ_SX'| '470UF'  | '2V'          | '20%'       | 'IO'       | 'CAP CHIP 470U 2V(+-20%,ESR9,7343,H1.9)'               | 'SMT'          | ''          | ''            | '20120326'
 '330UF'  | '2V'    | '20%'       | 'RDLLF'     | 'C_POSCAP' | 'CH733RM8866'(!)             = ''              | ''                 | 'CH733RM8866'                | 'TAJ_SX'                   | '330UF'  | '2V'          | '20%'       | 'DISCRETE' | 'CAP CHIP 330U 2V(20%,ESR=6,7343,H1.9)'                | 'SMT'          | ''          | ''            | '20120326'
 '330UF'  | '2V'    | '20%'       | 'RDLLF'     | 'EMPTY'    | 'CH733RM8866'(!)             = ''              | ''                 | 'CH733RM8866'                | 'TAJ_SX'                   | '330UF'  | '2V'          | '20%'       | 'IO'       | 'CAP CHIP 330U 2V(20%,ESR=6,7343,H1.9)'                | 'SMT'          | ''          | ''            | '20120326'
 '100UF'  | '16V'   | '20%'       | 'RDLLF'     | 'OSCON'    | 'CC71003MZ23'(!)             = ''              | ''                 | 'CC71003MZ23'                |'EC56_197_229S'| '100UF'  | '16V'         | '20%'       | 'DISCRETE' | 'CAP OSCON SMD 100U 16V(20%,105C,5*5.8)'               | 'SMT'          | ''          | ''            | '20120525'
 '100UF'  | '16V'   | '20%'       | 'RDLLF'     | 'EMPTY'    | 'CC71003MZ23'(!)             = ''              | ''                 | 'CC71003MZ23'                |'EC56_197_229S'| '100UF'  | '16V'         | '20%'       | 'IO'       | 'CAP OSCON SMD 100U 16V(20%,105C,5*5.8)'               | 'SMT'          | ''          | ''            | '20120525'
 '220U'   | '6.3V'  | '35%'       | 'RDLLF'     | 'C_POSCAP' | 'CH7221Y8800'(!)             = ''              | ''                 | 'CH7221Y8800'                |'TAJ_DXC'| '220U'   | '6.3V'        | '35%'       | 'DISCRETE' | 'CAP 220U 6.3V(+10/-35%,ESR15,7343)H1.9'               | 'SMT'          | ''          | ''            | '20120601'
 '220U'   | '6.3V'  | '35%'       | 'RDLLF'     | 'EMPTY'    | 'CH7221Y8800'(!)             = ''              | ''                 | 'CH7221Y8800'                |'TAJ_DXC'| '220U'   | '6.3V'        | '35%'       | 'IO'       | 'CAP 220U 6.3V(+10/-35%,ESR15,7343)H1.9'               | 'SMT'          | ''          | ''            | '20120601'
 '180UF'  | '16V'   | '20%'       | 'RDLLF'     | 'ALUM'     | 'CC71803MZ03'(!)             = ''              | ''                 | 'CC71803MZ03'                |'EC83_248_232S'| '180UF'  | '16V'         | '20%'       | 'DISCRETE' | 'CAP OSCON SMD 180U 16V(20%.105C.6.3*5.9))'            | 'SMT'          | ''          | ''            | '20120726'
 '180UF'  | '16V'   | '20%'       | 'RDLLF'     | 'EMPTY'    | 'CC71803MZ03'(!)             = ''              | ''                 | 'CC71803MZ03'                |'EC83_248_232S'| '180UF'  | '16V'         | '20%'       | 'IO'       | 'CAP OSCON SMD 180U 16V(20%.105C.6.3*5.9))'            | 'SMT'          | ''          | ''            | '20120726'
 '330UF'  | '2.5V'  | '20%'       | 'RDLLF'     | 'SP-CAP'   | 'CH733LM8800'(!)             = 'End of Design' | 'Comp-Approve'     | 'CH733LM8800'                |'TAJ_SX'| '330UF'  | '2.5V'        | '20%'       | 'DISCRETE' | 'CAP CHIP 330U 2.5V(+-20%,ESR6,7343)H1.9'              | 'SMT'          | ''          | ''            | '20120815'
 '330UF'  | '2.5V'  | '20%'       | 'RDLLF'     | 'EMPTY'    | 'CH733LM8800'(!)             = 'End of Design' | 'Comp-Approve'     | 'CH733LM8800'                |'TAJ_SX'| '330UF'  | '2.5V'        | '20%'       | 'IO'       | 'CAP CHIP 330U 2.5V(+-20%,ESR6,7343)H1.9'              | 'SMT'          | ''          | ''            | '20120815'
 '470UF'  | '10V'   | '20%'       | 'RDLLF'     | 'ALUM'     | 'CC74702MD03'(!)             = ''              | ''                 | 'CC74702MD03'                |'EC98_248_433'| '470UF'  | '10V'         | '20%'       | 'DISCRETE' | 'CAP ELEC DIP 470U 10V(+-20%,105C,6.3*11)'             | 'DIP'          | ''          | ''            | '20120924'
 '470UF'  | '10V'   | '20%'       | 'RDLLF'     | 'EMPTY'    | 'CC74702MD03'(!)             = ''              | ''                 | 'CC74702MD03'                |'EC98_248_433'| '470UF'  | '10V'         | '20%'       | 'IO'       | 'CAP ELEC DIP 470U 10V(+-20%,105C,6.3*11)'             | 'DIP'          | ''          | ''            | '20120924'
 '100UF'  | '16V'   | '20%'       | 'RDLLF'     | 'ALUM'     | 'CC71003MZ14'(!)             = 'End of Design' | 'Comp-Approve'     | 'CC71003MZ14'                |'EC71_248_229S'| '100UF'  | '16V'         | '20%'       | 'DISCRETE' | 'CAP SMD 100U 16V(+-20%,105C,6.3*5.8)'                 | 'SMT'          | ''          | ''            | '20121214'
 '100UF'  | '16V'   | '20%'       | 'RDLLF'     | 'EMPTY'    | 'CC71003MZ14'(!)             = 'End of Design' | 'Comp-Approve'     | 'CC71003MZ14'                |'EC71_248_229S'| '100UF'  | '16V'         | '20%'       | 'IO'       | 'CAP SMD 100U 16V(+-20%,105C,6.3*5.8)'                 | 'SMT'          | ''          | ''            | '20121214'
 '1F'     | '5.5V'  | '80%'       | 'RDLLF'     | 'ALUM'     | 'CCB1000ZD00'(!)             = ''              | ''                 | 'CCB1000ZD00'                |'EC297_847_512'| '1F'     | '5.5V'        | '80%'       | 'DISCRETE' | 'CAP ELEC DIP 1F 5.5V (+80%-20%,21.5*13)'              | 'DIP'          | ''          | ''            | '20130110'
 '1F'     | '5.5V'  | '80%'       | 'RDLLF'     | 'EMPTY'    | 'CCB1000ZD00'(!)             = ''              | ''                 | 'CCB1000ZD00'                |'EC297_847_512'| '1F'     | '5.5V'        | '80%'       | 'IO'       | 'CAP ELEC DIP 1F 5.5V (+80%-20%,21.5*13)'              | 'DIP'          | ''          | ''            | '20130110'
 '470UF'  | '2.5V'  | '20%'       | 'RDLF'      | 'POSCAP'   | 'CH747LM8814'(!)             = ''              | ''                 | 'CH747LM8814'                |'TAJ_SX'| '470UF'  | '2.5V'        | '20%'       | 'DISCRETE' | 'CAP CHIP 470U 2.5V(20%,ESR4.5,7343,H1.9)'             | 'SMT'          | ''          | ''            | '20130325'
 '470UF'  | '2.5V'  | '20%'       | 'RDLF'      | 'EMPTY'    | 'CH747LM8814'(!)             = ''              | ''                 | 'CH747LM8814'                |'TAJ_SX'| '470UF'  | '2.5V'        | '20%'       | 'IO'       | 'CAP CHIP 470U 2.5V(20%,ESR4.5,7343,H1.9)'             | 'SMT'          | ''          | ''            | '20130325'
 '560UF'  | '2.5V'  | '20%'       | 'RDLF'      | 'ALUM'     | 'CC7560JMD09'(!)             = ''              | ''                 | 'CC7560JMD09'                |'EC98_248_237'| '560UF'  | '2.5V'        | '20%'       | 'DISCRETE' | 'CAP OSCON DIP 560U 2.5V(20%,105C,6.3*6)'              | 'DIP'          | ''          | ''            | '20130403'
 '560UF'  | '2.5V'  | '20%'       | 'RDLF'      | 'EMPTY'    | 'CC7560JMD09'(!)             = ''              | ''                 | 'CC7560JMD09'                |'EC98_248_237'| '560UF'  | '2.5V'        | '20%'       | 'IO'       | 'CAP OSCON DIP 560U 2.5V(20%,105C,6.3*6)'              | 'DIP'          | ''          | ''            | '20130403'
 '220UF'  | '2.5V'  | '20%'       | 'SMLF'      | 'TANT'     | 'CH722LM8816'(!)             = ''              | ''                 | 'CH722LM8816'                |'TAJ_D2'| '220UF'  | '2.5V'        | '20%'       | 'DISCRETE' | 'CAP CHIP 220U2.5V(20%,ESR15,7343,H1.9)'               | 'SMT'          | ''          | ''            | '20130417'
 '220UF'  | '2.5V'  | '20%'       | 'SMLF'      | 'EMPTY'    | 'CH722LM8816'(!)             = ''              | ''                 | 'CH722LM8816'                |'TAJ_D2'| '220UF'  | '2.5V'        | '20%'       | 'IO'       | 'CAP CHIP 220U2.5V(20%,ESR15,7343,H1.9)'               | 'SMT'          | ''          | ''            | '20130417'
 '820UF'  | '16V'   | '20%'       | 'RDLF'      | 'ALUM'     | 'CC78203MD00'(!)             = ''              | ''                 | 'CC78203MD00'                |'EC197_394_453'| '820UF'  | '16V'         | '20%'       | 'DISCRETE' | 'CAP OSCON DIP 820U 16V(20%,105C,10*11.5)'             | 'DIP'          | ''          | ''            | '20130507'
 '820UF'  | '16V'   | '20%'       | 'RDLF'      | 'EMPTY'    | 'CC78203MD00'(!)             = ''              | ''                 | 'CC78203MD00'                |'EC197_394_453'| '820UF'  | '16V'         | '20%'       | 'IO'       | 'CAP OSCON DIP 820U 16V(20%,105C,10*11.5)'             | 'DIP'          | ''          | ''            | '20130507'
 '100UF'  | '100V'  | '20%'       | 'RDLF'      | 'ALUM'     | 'CC71008MD04'(!)             = 'End of Design' | 'P/N Release'      | 'CC71008MD04'                |'EC197_493_630'| '100UF'  | '100V'        | '20%'       | 'DISCRETE' | 'CAP ELEC DIP 100U 100V(20%,105C,12.5*16)'             | 'DIP'          | ''          | ''            | '20130521'
 '100UF'  | '100V'  | '20%'       | 'RDLF'      | 'EMPTY'    | 'CC71008MD04'(!)             = 'End of Design' | 'P/N Release'      | 'CC71008MD04'                |'EC197_493_630'| '100UF'  | '100V'        | '20%'       | 'IO'       | 'CAP ELEC DIP 100U 100V(20%,105C,12.5*16)'             | 'DIP'          | ''          | ''            | '20130521'
 '470UF'  | '16V'   | '20%'       | 'RDLF'      | 'OSCON'    | 'CC74703MD24'(!)             = ''              | ''                 | 'CC74703MD24'                |'EC3-5_8-5_9'| '470UF'  | '16V'         | '20%'       | 'DISCRETE' | 'CAP OSCON DIP 470U 16V(+-20%,ESR16,8*8)'              | 'DIP'          | ''          | ''            | '20130528'
 '470UF'  | '16V'   | '20%'       | 'RDLF'      | 'EMPTY'    | 'CC74703MD24'(!)             = ''              | ''                 | 'CC74703MD24'                |'EC3-5_8-5_9'| '470UF'  | '16V'         | '20%'       | 'IO'       | 'CAP OSCON DIP 470U 16V(+-20%,ESR16,8*8)'              | 'DIP'          | ''          | ''            | '20130528'
 '100UF'  | '10V'   | '20%'       | 'SMLF'      | 'TANT'     | 'CH7102MT800'(!)             = ''              | ''                 | 'CH7102MT800'                |'TAJ_D3L'| '100UF'  | '10V'         | '20%'       | 'DISCRETE' | 'CAPCHIP 100U 10V(20%,ESR55,TAN,7343)H2.8'             | 'SMT'          | ''          | ''            | '20130802'
 '100UF'  | '10V'   | '20%'       | 'SMLF'      | 'EMPTY'    | 'CH7102MT800'(!)             = ''              | ''                 | 'CH7102MT800'                |'TAJ_D3L'| '100UF'  | '10V'         | '20%'       | 'IO'       | 'CAPCHIP 100U 10V(20%,ESR55,TAN,7343)H2.8'             | 'SMT'          | ''          | ''            | '20130802'
 '33UF'   | '16V'   | '20%'       | 'SMLF'      | 'TANT'     | 'CH6333M8807'(!)             = 'End of Design' | 'Comp-Approve'     | 'CH6333M8807'                |'TAJ_D2'| '33UF'   | '16V'         | '20%'       | 'DISCRETE' | 'CAP CHIP 33U 16V(+-20%,ESR60,7343)H1.9EP'             | 'SMT'          | ''          | ''            | '20130904'
 '33UF'   | '16V'   | '20%'       | 'SMLF'      | 'EMPTY'    | 'CH6333M8807'(!)             = 'End of Design' | 'Comp-Approve'     | 'CH6333M8807'                |'TAJ_D2'| '33UF'   | '16V'         | '20%'       | 'IO'       | 'CAP CHIP 33U 16V(+-20%,ESR60,7343)H1.9EP'             | 'SMT'          | ''          | ''            | '20130904'
 '560UF'  | '2.5V'  | '20%'       | 'RDLF'      | 'OSCON'    | 'SP_CC7560JMD07'(!)          = 'End of Design' | 'Comp-Release Qty' | 'CC7560JMD07'                |'EC98_248_237_T6MG'| '560UF'  | '2.5V'        | '20%'       | 'DISCRETE' | 'CAP OS-C 560U 2.5V(20%,ESR13,6.3*5)'                  | 'DIP'          | ''          | ''            | '20131018'
 '560UF'  | '2.5V'  | '20%'       | 'RDLF'      | 'EMPTY'    | 'SP_CC7560JMD07'(!)          = 'End of Design' | 'Comp-Release Qty' | 'CC7560JMD07'                |'EC98_248_237_T6MG'| '560UF'  | '2.5V'        | '20%'       | 'IO'       | 'CAP OS-C 560U 2.5V(20%,ESR13,6.3*5)'                  | 'DIP'          | ''          | ''            | '20131018'
 '270UF'  | '16V'   | '20%'       | 'RDLF'      | 'OSCON'    | 'SP_CC72703MD03-1'(!)        = ''              | ''                 | 'CC72703MD03'                |'EC138_315_354A_T6MG'| '270UF'  | '16V'         | '20%'       | 'DISCRETE' | 'CAP OSCON DIP 270U 16V(+-20%,8*9)'                    | 'DIP'          | ''          | ''            | '20131018'
 '270UF'  | '16V'   | '20%'       | 'RDLF'      | 'EMPTY'    | 'SP_CC72703MD03-1'(!)        = ''              | ''                 | 'CC72703MD03'                |'EC138_315_354A_T6MG'| '270UF'  | '16V'         | '20%'       | 'IO'       | 'CAP OSCON DIP 270U 16V(+-20%,8*9)'                    | 'DIP'          | ''          | ''            | '20131018'
 '820UF'  | '2.5V'  | '20%'       | 'RDLF'      | 'OSCON'    | 'SP_CC7820JMD01-1'(!)        = ''              | ''                 | 'CC7820JMD01'                |'EC98_248_315_T6MG'| '820UF'  | '2.5V'        | '20%'       | 'DISCRETE' | 'CAP OSCON DIP 820U 2.5V(+-20%,6.3*8)'                 | 'DIP'          | ''          | ''            | '20131018'
 '820UF'  | '2.5V'  | '20%'       | 'RDLF'      | 'EMPTY'    | 'SP_CC7820JMD01-1'(!)        = ''              | ''                 | 'CC7820JMD01'                |'EC98_248_315_T6MG'| '820UF'  | '2.5V'        | '20%'       | 'IO'       | 'CAP OSCON DIP 820U 2.5V(+-20%,6.3*8)'                 | 'DIP'          | ''          | ''            | '20131018'
 '270UF'  | '16V'   | '20%'       | 'RDLF'      | 'OSCON'    | 'SP_CC72703MD19-1'(!)        = ''              | ''                 | 'CC72703MD19'                |'EC98_248_315_T6MG'| '270UF'  | '16V'         | '20%'       | 'DISCRETE' | 'CAP OSCON DIP 270U 16V(20%,105C,6.3*8)'               | 'DIP'          | ''          | ''            | '20131018'
 '270UF'  | '16V'   | '20%'       | 'RDLF'      | 'EMPTY'    | 'SP_CC72703MD19-1'(!)        = ''              | ''                 | 'CC72703MD19'                |'EC98_248_315_T6MG'| '270UF'  | '16V'         | '20%'       | 'IO'       | 'CAP OSCON DIP 270U 16V(20%,105C,6.3*8)'               | 'DIP'          | ''          | ''            | '20131018'
 '560UF'  | '6.3V'  | '20%'       | 'RDLF'      | 'OSCON'    | 'SP_CC75601MD01-1'(!)        = ''              | ''                 | 'CC75601MD01'                |'EC98_248_315_T6MG'| '560UF'  | '6.3V'        | '20%'       | 'DISCRETE' | 'CAP OSCON DIP 560U 6.3V(+-20%,6.3*8)'                 | 'DIP'          | ''          | ''            | '20131018'
 '560UF'  | '6.3V'  | '20%'       | 'RDLF'      | 'EMPTY'    | 'SP_CC75601MD01-1'(!)        = ''              | ''                 | 'CC75601MD01'                |'EC98_248_315_T6MG'| '560UF'  | '6.3V'        | '20%'       | 'IO'       | 'CAP OSCON DIP 560U 6.3V(+-20%,6.3*8)'                 | 'DIP'          | ''          | ''            | '20131018'
 '560UF'  | '2.5V'  | '20%'       | 'RDLF'      | 'OSCON'    | 'CC7560JMD07'(!)             = 'End of Design' | 'Comp-Release Qty' | 'CC7560JMD07'                |'EC98_248_237'| '560UF'  | '2.5V'        | '20%'       | 'DISCRETE' | 'CAP OS-C 560U 2.5V(20%,ESR13,6.3*5)'                  | 'DIP'          | ''          | ''            | '20131018'
 '560UF'  | '2.5V'  | '20%'       | 'RDLF'      | 'EMPTY'    | 'CC7560JMD07'(!)             = 'End of Design' | 'Comp-Release Qty' | 'CC7560JMD07'                |'EC98_248_237'| '560UF'  | '2.5V'        | '20%'       | 'IO'       | 'CAP OS-C 560U 2.5V(20%,ESR13,6.3*5)'                  | 'DIP'          | ''          | ''            | '20131018'
 '270UF'  | '16V'   | '20%'       | 'RDLF'      | 'OSCON'    | 'CC72703MD19'(!)             = ''              | ''                 | 'CC72703MD19'                |'EC2-5_6-8_9'| '270UF'  | '16V'         | '20%'       | 'DISCRETE' | 'CAP OSCON DIP 270U 16V(20%,105C,6.3*8)'               | 'DIP'          | ''          | ''            | '20131018'
 '270UF'  | '16V'   | '20%'       | 'RDLF'      | 'EMPTY'    | 'CC72703MD19'(!)             = ''              | ''                 | 'CC72703MD19'                |'EC2-5_6-8_9'| '270UF'  | '16V'         | '20%'       | 'IO'       | 'CAP OSCON DIP 270U 16V(20%,105C,6.3*8)'               | 'DIP'          | ''          | ''            | '20131018'
 '330UF'  | '6.3V'  | '20%'       | 'SMLF'      | 'POSCAP'   | 'CH7331M8851'(!)             = 'End of Design' | 'Comp-Approve'     | 'CH7331M8851'                |'TAJ_D3L'| '330UF'  | '6.3V'        | '20%'       | 'DISCRETE' | 'CAP CHIP330U 6.3V(20%,ESR18,7343,H2.8)'               | 'SMT'          | ''          | ''            | '20131024'
 '330UF'  | '6.3V'  | '20%'       | 'SMLF'      | 'EMPTY'    | 'CH7331M8851'(!)             = 'End of Design' | 'Comp-Approve'     | 'CH7331M8851'                |'TAJ_D3L'| '330UF'  | '6.3V'        | '20%'       | 'IO'       | 'CAP CHIP330U 6.3V(20%,ESR18,7343,H2.8)'               | 'SMT'          | ''          | ''            | '20131024'
 '470UF'  | '16V'   | '20%'       | 'SMLF'      | 'ALUM'     | 'CC74703MZ00'(!)             = ''              | ''                 | 'CC74703MZ00'                |'EC123_315_394S'| '470UF'  | '16V'         | '20%'       | 'DISCRETE' | 'CAP ELEC SMD 470U 16V(+-20%,105C,8*10)'               | 'SMT'          | ''          | ''            | '20131105'
 '470UF'  | '16V'   | '20%'       | 'SMLF'      | 'EMPTY'    | 'CC74703MZ00'(!)             = ''              | ''                 | 'CC74703MZ00'                |'EC123_315_394S'| '470UF'  | '16V'         | '20%'       | 'IO'       | 'CAP ELEC SMD 470U 16V(+-20%,105C,8*10)'               | 'SMT'          | ''          | ''            | '20131105'
 '47UF'   | '100V'  | '20%'       | 'RDLF'      | 'ALUM'     | 'SP_CC64708MD01_1'(!)        = ''              | ''                 | 'CC64708MD01'                |'G_EC197_394_492_T2L'| '47UF'   | '100V'        | '20%'       | 'DISCRETE' | 'CAP ELEC DIP 47U 100V(20%,105C,10*12.5)'              | 'DIP'          | ''          | ''            | '20131114'
 '47UF'   | '100V'  | '20%'       | 'RDLF'      | 'EMPTY'    | 'SP_CC64708MD01_1'(!)        = ''              | ''                 | 'CC64708MD01'                |'G_EC197_394_492_T2L'| '47UF'   | '100V'        | '20%'       | 'IO'       | 'CAP ELEC DIP 47U 100V(20%,105C,10*12.5)'              | 'DIP'          | ''          | ''            | '20131114'
 '330UF'  | '6.3V'  | '20%'       | 'SMLF'      | 'POSCAP'   | 'CH7331M8826'(!)             = ''              | 'Comp-Approve'     | 'CH7331M8826'                | 'TAJ_D2E'                  | '330UF'  | '6.3V'        | '20%'       | 'DISCRETE' | 'CAP 330U 6.3V(+-20%,ESR25M,7343,H=1.9)'               | 'SMT'          | ''          | ''            | '20131216'
 '330UF'  | '6.3V'  | '20%'       | 'SMLF'      | 'EMPTY'    | 'CH7331M8826'(!)             = ''              | 'Comp-Approve'     | 'CH7331M8826'                | 'TAJ_D2E'                  | '330UF'  | '6.3V'        | '20%'       | 'IO'       | 'CAP 330U 6.3V(+-20%,ESR25M,7343,H=1.9)'               | 'SMT'          | ''          | ''            | '20131216'
 '330UF'  | '2.5V'  | '20%'       | 'SMLF'      | 'POSCAP'   | 'CH733LM8604'(!)             = ''              | ''                 | 'CH733LM8604'                |'TAJ_B2XA'| '330UF'  | '2.5V'        | '20%'       | 'DISCRETE' | 'CAP CHIP 330U 2.5V(+-20%,ESR9,3528)H1.9'              | 'SMT'          | ''          | ''            | '20131218'
 '330UF'  | '2.5V'  | '20%'       | 'SMLF'      | 'EMPTY'    | 'CH733LM8604'(!)             = ''              | ''                 | 'CH733LM8604'                |'TAJ_B2XA'| '330UF'  | '2.5V'        | '20%'       | 'IO'       | 'CAP CHIP 330U 2.5V(+-20%,ESR9,3528)H1.9'              | 'SMT'          | ''          | ''            | '20131218'
 '560UF'  | '2V'    | '20%'       | 'SMLF'      | 'POSCAP'   | 'CH756RM8802'(!)             = ''              | ''                 | 'CH756RM8802'                |'TAJ_SX'| '560UF'  | '2V'          | '20%'       | 'DISCRETE' | 'CAP CHIP 560U 2V(20%,ESR4.5,7343,H1.9)'               | 'SMT'          | ''          | ''            | '20140116'
 '560UF'  | '2V'    | '20%'       | 'SMLF'      | 'EMPTY'    | 'CH756RM8802'(!)             = ''              | ''                 | 'CH756RM8802'                |'TAJ_SX'| '560UF'  | '2V'          | '20%'       | 'IO'       | 'CAP CHIP 560U 2V(20%,ESR4.5,7343,H1.9)'               | 'SMT'          | ''          | ''            | '20140116'
 '470UF'  | '2.5V'  | '20%'       | 'SMLF'      | 'POSCAP'   | 'CH747LM8816'(!)             = ''              | ''                 | 'CH747LM8816'                |'TAJ_DXC'| '470UF'  | '2.5V'        | '20%'       | 'DISCRETE' | 'CAP CHIP 470U 2.5V(20%,ESR3M,7343,SPCAP)'             | 'SMT'          | ''          | ''            | '20140121'
 '470UF'  | '2.5V'  | '20%'       | 'SMLF'      | 'EMPTY'    | 'CH747LM8816'(!)             = ''              | ''                 | 'CH747LM8816'                |'TAJ_DXC'| '470UF'  | '2.5V'        | '20%'       | 'IO'       | 'CAP CHIP 470U 2.5V(20%,ESR3M,7343,SPCAP)'             | 'SMT'          | ''          | ''            | '20140121'
 '470UF'  | '16V'   | '20%'       | 'SMLF'      | 'OSCON'    | 'CC74703MZ05'(!)             = ''              | ''                 | 'CC74703MZ05'                |'EC181_394_496SXA'| '470UF'  | '16V'         | '20%'       | 'DISCRETE' | 'CAP OSCON SMD 470UF 16V(105C,20%,10*12.6'             | 'SMT'          | ''          | ''            | '20221116'
 '470UF'  | '16V'   | '20%'       | 'SMLF'      | 'EMPTY'    | 'CC74703MZ05'(!)             = ''              | ''                 | 'CC74703MZ05'                |'EC181_394_496SXA'| '470UF'  | '16V'         | '20%'       | 'IO'       | 'CAP OSCON SMD 470UF 16V(105C,20%,10*12.6'             | 'SMT'          | ''          | ''            | '20221116'
 '100UF'  | '16V'   | '20%'       | 'SMLF'      | 'ALUM'     | 'CH7103M8803'(!)             = 'End of Design' | 'Comp-Approve'     | 'CH7103M8803'                |'TAJ_D9'| '100UF'  | '16V'         | '20%'       | 'DISCRETE' | 'CAP CHIP 100UF 16V(20%,ESR12,SPCAP,7343)'             | 'SMT'          | ''          | ''            | '20140326'
 '100UF'  | '16V'   | '20%'       | 'SMLF'      | 'EMPTY'    | 'CH7103M8803'(!)             = 'End of Design' | 'Comp-Approve'     | 'CH7103M8803'                |'TAJ_D9'| '100UF'  | '16V'         | '20%'       | 'IO'       | 'CAP CHIP 100UF 16V(20%,ESR12,SPCAP,7343)'             | 'SMT'          | ''          | ''            | '20140326'
 '470UF'  | '6.3V'  | '20%'       | 'SMLF'      | 'ALUM'     | 'CH7471MI800'(!)             = ''              | ''                 | 'CH7471MI800'                |'TAJ_D4XA_H158'| '470UF'  | '6.3V'        | '20%'       | 'DISCRETE' | 'CAP CHIP 470U 6.3V(20%,POSCAP(TAN),7343)'             | 'SMT'          | ''          | ''            | '20140326'
 '470UF'  | '6.3V'  | '20%'       | 'SMLF'      | 'EMPTY'    | 'CH7471MI800'(!)             = ''              | ''                 | 'CH7471MI800'                |'TAJ_D4XA_H158'| '470UF'  | '6.3V'        | '20%'       | 'IO'       | 'CAP CHIP 470U 6.3V(20%,POSCAP(TAN),7343)'             | 'SMT'          | ''          | ''            | '20140326'
 '100UF'  | '16V'   | '20%'       | 'SMLF'      | 'OSCON'    | 'CC71003MZ11'(!)             = ''              | ''                 | 'CC71003MZ11'                |'EC83_248_225S'| '100UF'  | '16V'         | '20%'       | 'DISCRETE' | 'CAP OSCON SMD 100U 16V(20%.105C.6.3*5.7)'             | 'SMT'          | ''          | ''            | '20140327'
 '100UF'  | '16V'   | '20%'       | 'SMLF'      | 'EMPTY'    | 'CC71003MZ11'(!)             = ''              | ''                 | 'CC71003MZ11'                |'EC83_248_225S'| '100UF'  | '16V'         | '20%'       | 'IO'       | 'CAP OSCON SMD 100U 16V(20%.105C.6.3*5.7)'             | 'SMT'          | ''          | ''            | '20140327'
 '47UF'   | '100V'  | '20%'       | 'RDLF'      | 'ALUM'     | 'CC64708MD02'(!)             = 'End of Design' | 'Comp-Approve'     | 'CC64708MD02'                |'EC3-5_8-5_13'| '47UF'   | '100V'        | '20%'       | 'DISCRETE' | 'CAP ELEC DIP 47U 100V(20%,105C,8*11.5)'               | 'DIP'          | ''          | ''            | '20140331'
 '47UF'   | '100V'  | '20%'       | 'RDLF'      | 'EMPTY'    | 'CC64708MD02'(!)             = 'End of Design' | 'Comp-Approve'     | 'CC64708MD02'                |'EC3-5_8-5_13'| '47UF'   | '100V'        | '20%'       | 'IO'       | 'CAP ELEC DIP 47U 100V(20%,105C,8*11.5)'               | 'DIP'          | ''          | ''            | '20140331'
 '100UF'  | '100V'  | '20%'       | 'RDLF'      | 'ALUM'     | 'CC71008MD05'(!)             = ''              | ''                 | 'CC71008MD05'                |'EC197_394_630'| '100UF'  | '100V'        | '20%'       | 'DISCRETE' | 'CAP ELEC DIP 100U 100V(20%,105C,10*16)'               | 'DIP'          | ''          | ''            | '20140331'
 '100UF'  | '100V'  | '20%'       | 'RDLF'      | 'EMPTY'    | 'CC71008MD05'(!)             = ''              | ''                 | 'CC71008MD05'                |'EC197_394_630'| '100UF'  | '100V'        | '20%'       | 'IO'       | 'CAP ELEC DIP 100U 100V(20%,105C,10*16)'               | 'DIP'          | ''          | ''            | '20140331'
 '680UF'  | '2.5V'  | '20%'       | 'SMLF'      | 'ESR7'     | 'CH768LM8819'(!)             = ''              | ''                 | 'CH768LM8819'                |'TAJ_DXD'| '680UF'  | '2.5V'        | '20%'       | 'DISCRETE' | 'CAP CHIP 680U 2.5V (20%,ESR7,7343,H2.8)'              | 'SMT'          | ''          | ''            | '20140429'
 '680UF'  | '2.5V'  | '20%'       | 'SMLF'      | 'EMPTY'    | 'CH768LM8819'(!)             = ''              | ''                 | 'CH768LM8819'                |'TAJ_DXD'| '680UF'  | '2.5V'        | '20%'       | 'IO'       | 'CAP CHIP 680U 2.5V (20%,ESR7,7343,H2.8)'              | 'SMT'          | ''          | ''            | '20140429'
 '680UF'  | '16V'   | '20%'       | 'SMLF'      | 'ALUM'     | 'CC76803MZ11'(!)             = ''              | ''                 | 'CC76803MZ11'                |'EC181_394_402S'| '680UF'  | '16V'         | '20%'       | 'DISCRETE' | 'CAP ELEC SMD 680U 16V(20%,105,10X10)'                 | 'SMT'          | ''          | ''            | '20140610'
 '680UF'  | '16V'   | '20%'       | 'SMLF'      | 'EMPTY'    | 'CC76803MZ11'(!)             = ''              | ''                 | 'CC76803MZ11'                |'EC181_394_402S'| '680UF'  | '16V'         | '20%'       | 'IO'       | 'CAP ELEC SMD 680U 16V(20%,105,10X10)'                 | 'SMT'          | ''          | ''            | '20140610'
 '680UF'  | '6.3V'  | '20%'       | 'SMLF'      | 'TANT'     | 'TMP_S2B_ALVIN_0526_1'(!)    = ''              | ''                 | 'TMP_S2B_ALVIN_0526_1'       | 'TAJ_D4XA'                 | '680UF'  | '6.3V'        | '20%'       | 'DISCRETE' | 'CAP 680U 6.3V (+-20%.ESR25M.7343.H=3.8)'              | 'SMT'          | ''          | ''            | '20140527'
 '680UF'  | '6.3V'  | '20%'       | 'SMLF'      | 'EMPTY'    | 'TMP_S2B_ALVIN_0526_1'(!)    = ''              | ''                 | 'TMP_S2B_ALVIN_0526_1'       | 'TAJ_D4XA'                 | '680UF'  | '6.3V'        | '20%'       | 'IO'       | 'CAP 680U 6.3V (+-20%.ESR25M.7343.H=3.8)'              | 'SMT'          | ''          | ''            | '20140527'
 '680UF'  | '4V'    | '20%'       | 'SMLF'      | 'TANT'     | 'CH7680KMT80'(!)             = ''              | ''                 | 'CH7680KMT80'                |'TAJ_D4'| '680UF'  | '4V'          | '20%'       | 'DISCRETE' | 'CAP CHIP 680U 4V(20%,ESR5,7343,TAN)H3.8'              | 'SMT'          | ''          | ''            | '20140527'
 '680UF'  | '4V'    | '20%'       | 'SMLF'      | 'EMPTY'    | 'CH7680KMT80'(!)             = ''              | ''                 | 'CH7680KMT80'                |'TAJ_D4'| '680UF'  | '4V'          | '20%'       | 'IO'       | 'CAP CHIP 680U 4V(20%,ESR5,7343,TAN)H3.8'              | 'SMT'          | ''          | ''            | '20140527'
 '10UF'   | '100V'  | '20%'       | 'SMLF'      | 'ALUM'     | 'CC61008MZ01'(!)             = ''              | ''                 | 'CC61008MZ01'                |'EC75_248_303S'| '10UF'   | '100V'        | '20%'       | 'DISCRETE' | 'CAP ELEC 10U 100V(+-20%,105C,6.3*7.7)'                | 'SMT'          | ''          | ''            | '2010722' 
 '10UF'   | '100V'  | '20%'       | 'SMLF'      | 'EMPTY'    | 'CC61008MZ01'(!)             = ''              | ''                 | 'CC61008MZ01'                |'EC75_248_303S'| '10UF'   | '100V'        | '20%'       | 'IO'       | 'CAP ELEC 10U 100V(+-20%,105C,6.3*7.7)'                | 'SMT'          | ''          | ''            | '2010722' 
 '330UF'  | '16V'   | '20%'       | 'SMLF'      | 'TANT'     | 'CH7333MT800'(!)             = 'Potential'     | 'End of Life'      | 'CH7333MT800'                |'TAJ_D4_EOL'| '330UF'  | '16V'         | '20%'       | 'DISCRETE' | 'CAP CHIP 330U 16V(+-20%,TAN,7343,H4.0)'               | 'SMT'          | ''          | ''            | '20140731'
 '330UF'  | '16V'   | '20%'       | 'SMLF'      | 'EMPTY'    | 'CH7333MT800'(!)             = 'Potential'     | 'End of Life'      | 'CH7333MT800'                |'TAJ_D4_EOL'| '330UF'  | '16V'         | '20%'       | 'IO'       | 'CAP CHIP 330U 16V(+-20%,TAN,7343,H4.0)'               | 'SMT'          | ''          | ''            | '20140731'
 '220UF'  | '100V'  | '20%'       | 'RDLF'      | 'ALUM'     | 'CC72208MD02'(!)             = ''              | ''                 | 'CC72208MD02'                |'EC197_493_985'| '220UF'  | '100V'        | '20%'       | 'DISCRETE' | 'CAPELECDIP 220U 100V(20%,ESR0.06,12.5*25'             | 'DIP'          | ''          | ''            | '20140806'
 '220UF'  | '100V'  | '20%'       | 'RDLF'      | 'EMPTY'    | 'CC72208MD02'(!)             = ''              | ''                 | 'CC72208MD02'                |'EC197_493_985'| '220UF'  | '100V'        | '20%'       | 'IO'       | 'CAPELECDIP 220U 100V(20%,ESR0.06,12.5*25'             | 'DIP'          | ''          | ''            | '20140806'
 '560UF'  | '2.5V'  | '20%'       | 'RDLF'      | 'ALUM'     | 'CC7560JMD11'(!)             = ''              | 'End of Life'      | 'CC7560JMD11'                |'EC98_248_237_EOL'| '560UF'  | '2.5V'        | '20%'       | 'DISCRETE' | 'CAP ELEC DIP 560U 2.5V(20%,105C,6.3*6)'               | 'DIP'          | ''          | ''            | '20140806'
 '560UF'  | '2.5V'  | '20%'       | 'RDLF'      | 'EMPTY'    | 'CC7560JMD11'(!)             = ''              | 'End of Life'      | 'CC7560JMD11'                |'EC98_248_237_EOL'| '560UF'  | '2.5V'        | '20%'       | 'IO'       | 'CAP ELEC DIP 560U 2.5V(20%,105C,6.3*6)'               | 'DIP'          | ''          | ''            | '20140806'
 '470UF'  | '2V'    | '20%'       | 'SMLF'      | 'TANT'     | 'CH747RM8807'(!)             = 'End of Design' | 'Comp-Approve'     | 'CH747RM8807'                |'TAJ_LX'| '470UF'  | '2V'          | '20%'       | 'DISCRETE' | 'CAP CHIP 470U 2V(20%,ESR4.5,7343,H1.9)3P'             | 'SMT'          | ''          | ''            | '20140813'
 '470UF'  | '2V'    | '20%'       | 'SMLF'      | 'EMPTY'    | 'CH747RM8807'(!)             = 'End of Design' | 'Comp-Approve'     | 'CH747RM8807'                |'TAJ_LX'| '470UF'  | '2V'          | '20%'       | 'IO'       | 'CAP CHIP 470U 2V(20%,ESR4.5,7343,H1.9)3P'             | 'SMT'          | ''          | ''            | '20140813'
 '270UF'  | '16V'   | '20%'       | 'SMLF'      | 'OSCON'    | 'CC72703MZ00'(!)             = ''              | ''                 | 'CC72703MZ00'                |'EC126_315_272S'| '270UF'  | '16V'         | '20%'       | 'DISCRETE' | 'CAP OSCON SMD 270U 16V(20%.105C.8*6.9)'               | 'SMT'          | ''          | ''            | '20140819'
 '270UF'  | '16V'   | '20%'       | 'SMLF'      | 'EMPTY'    | 'CC72703MZ00'(!)             = ''              | ''                 | 'CC72703MZ00'                |'EC126_315_272S'| '270UF'  | '16V'         | '20%'       | 'IO'       | 'CAP OSCON SMD 270U 16V(20%.105C.8*6.9)'               | 'SMT'          | ''          | ''            | '20140819'
 '22UF'   | '25V'   | '20%'       | 'SMLF'      | 'ALUM'     | 'CC62204MZ39'(!)             = ''              | ''                 | 'CC62204MZ39'                |'EC71_248_213S'| '22UF'   | '25V'         | '20%'       | 'DISCRETE' | 'CAP ELEC SMD 22U 25V(+-20%,85C,6.3*5.4)'              | 'SMT'          | ''          | ''            | '20140825'
 '22UF'   | '25V'   | '20%'       | 'SMLF'      | 'EMPTY'    | 'CC62204MZ39'(!)             = ''              | ''                 | 'CC62204MZ39'                |'EC71_248_213S'| '22UF'   | '25V'         | '20%'       | 'IO'       | 'CAP ELEC SMD 22U 25V(+-20%,85C,6.3*5.4)'              | 'SMT'          | ''          | ''            | '20140825'
 '100UF'  | '16V'   | '20%'       | 'SMLF'      | 'POSCAP'   | 'TH7103MI800'(!)             = ''              | ''                 | 'TH7103MI800'                |'TAJ_D2'| '100UF'  | '16V'         | '20%'       | 'DISCRETE' | 'CAP CHIP 100U 16V(20%,POSCAP,7343)EMSSEL'             | 'SMT'          | ''          | ''            | '20140825'
 '100UF'  | '16V'   | '20%'       | 'SMLF'      | 'EMPTY'    | 'TH7103MI800'(!)             = ''              | ''                 | 'TH7103MI800'                |'TAJ_D2'| '100UF'  | '16V'         | '20%'       | 'IO'       | 'CAP CHIP 100U 16V(20%,POSCAP,7343)EMSSEL'             | 'SMT'          | ''          | ''            | '20140825'
 '270UF'  | '16V'   | '20%'       | 'RDLF'      | 'ALUM'     | 'CC72703MD23'(!)             = ''              | ''                 | 'CC72703MD23'                |'EC2-5_6-8_9'| '270UF'  | '16V'         | '20%'       | 'DISCRETE' | 'CAP ELEC DIP 270U 16V(20% ESR9.5 6.3*9)'              | 'DIP'          | ''          | ''            | '20140827'
 '270UF'  | '16V'   | '20%'       | 'RDLF'      | 'EMPTY'    | 'CC72703MD23'(!)             = ''              | ''                 | 'CC72703MD23'                |'EC2-5_6-8_9'| '270UF'  | '16V'         | '20%'       | 'IO'       | 'CAP ELEC DIP 270U 16V(20% ESR9.5 6.3*9)'              | 'DIP'          | ''          | ''            | '20140827'
 '560UF'  | '6.3V'  | '20%'       | 'RDLF'      | 'ALUM'     | 'CC75601MD12'(!)             = ''              | ''                 | 'CC75601MD12'                |'EC98_248_354XA'| '560UF'  | '6.3V'        | '20%'       | 'DISCRETE' | 'CAP ELEC DIP 560U 6.3V(20% ESR6.5 6.3*9'              | 'DIP'          | ''          | ''            | '20140827'
 '560UF'  | '6.3V'  | '20%'       | 'RDLF'      | 'EMPTY'    | 'CC75601MD12'(!)             = ''              | ''                 | 'CC75601MD12'                |'EC98_248_354XA'| '560UF'  | '6.3V'        | '20%'       | 'IO'       | 'CAP ELEC DIP 560U 6.3V(20% ESR6.5 6.3*9'              | 'DIP'          | ''          | ''            | '20140827'
 '820UF'  | '2.5V'  | '20%'       | 'RDLF'      | 'ALUM'     | 'CC7820JMD10'(!)             = ''              | ''                 | 'CC7820JMD10'                |'EC98_248_354'| '820UF'  | '2.5V'        | '20%'       | 'DISCRETE' | 'CAP ELEC DIP 820U 2.5V(20% ESR6.5 6.3*9'              | 'DIP'          | ''          | ''            | '20140827'
 '820UF'  | '2.5V'  | '20%'       | 'RDLF'      | 'EMPTY'    | 'CC7820JMD10'(!)             = ''              | ''                 | 'CC7820JMD10'                |'EC98_248_354'| '820UF'  | '2.5V'        | '20%'       | 'IO'       | 'CAP ELEC DIP 820U 2.5V(20% ESR6.5 6.3*9'              | 'DIP'          | ''          | ''            | '20140827'
 '560UF'  | '2.5V'  | '20%'       | 'RDLF'      | 'ALUM'     | 'CC7560JMD12'(!)             = ''              | ''                 | 'CC7560JMD12'                |'EC2_5-5_9XB'| '560UF'  | '2.5V'        | '20%'       | 'DISCRETE' | 'CAP ELEC DIP 560U 2.5V(20% ESR6.5 5*9)'               | 'DIP'          | ''          | ''            | '20140827'
 '560UF'  | '2.5V'  | '20%'       | 'RDLF'      | 'EMPTY'    | 'CC7560JMD12'(!)             = ''              | ''                 | 'CC7560JMD12'                |'EC2_5-5_9XB'| '560UF'  | '2.5V'        | '20%'       | 'IO'       | 'CAP ELEC DIP 560U 2.5V(20% ESR6.5 5*9)'               | 'DIP'          | ''          | ''            | '20140827'
 '100UF'  | '100V'  | '20%'       | 'RDLF'      | 'ALUM'     | 'CC71008MD06'(!)             = ''              | ''                 | 'CC71008MD06'                |'EC197_493_630'| '100UF'  | '100V'        | '20%'       | 'DISCRETE' | 'CAPELECDIP 100U 100V(20%,ESR0.13,12.5*16'             | 'DIP'          | ''          | ''            | '20140915'
 '100UF'  | '100V'  | '20%'       | 'RDLF'      | 'EMPTY'    | 'CC71008MD06'(!)             = ''              | ''                 | 'CC71008MD06'                |'EC197_493_630'| '100UF'  | '100V'        | '20%'       | 'IO'       | 'CAPELECDIP 100U 100V(20%,ESR0.13,12.5*16'             | 'DIP'          | ''          | ''            | '20140915'
 '100UF'  | '100V'  | '20%'       | 'RDLF_SEL'  | 'ALUM'     | 'SP_CC71008MD06'(!)          = ''              | ''                 | 'CC71008MD06'                |'G_EC197_493_630'| '100UF'  | '100V'        | '20%'       | 'DISCRETE' | 'CAPELECDIP 100U 100V(20%,ESR0.13,12.5*16'             | 'DIP'          | ''          | ''            | '20140915'
 '100UF'  | '100V'  | '20%'       | 'RDLF_SEL'  | 'EMPTY'    | 'SP_CC71008MD06'(!)          = ''              | ''                 | 'CC71008MD06'                |'G_EC197_493_630'| '100UF'  | '100V'        | '20%'       | 'IO'       | 'CAPELECDIP 100U 100V(20%,ESR0.13,12.5*16'             | 'DIP'          | ''          | ''            | '20140915'
 '0.33F'  | '5.5V'  | '30%'       | 'RDLF'      | 'ALUM'     | 'CCA3300TD01'(!)             = ''              | ''                 | 'CCA3300TD01'                |'EC197_394'| '0.33F'  | '5.5V'        | '30%'       | 'DISCRETE' | 'CAP ELEC DIP 0.33F 5.5V(30%,85C,11.5*5)'              | 'DIP'          | ''          | ''            | '20141006'
 '0.33F'  | '5.5V'  | '30%'       | 'RDLF'      | 'EMPTY'    | 'CCA3300TD01'(!)             = ''              | ''                 | 'CCA3300TD01'                |'EC197_394'| '0.33F'  | '5.5V'        | '30%'       | 'IO'       | 'CAP ELEC DIP 0.33F 5.5V(30%,85C,11.5*5)'              | 'DIP'          | ''          | ''            | '20141006'
 '560UF'  | '2.5V'  | '20%'       | 'RDLF_SEL'  | 'OSCON'    | 'CC7560JMD05'(!)             = ''              | ''                 | 'CC7560JMD05'                |'G_EC78_197_355'| '560UF'  | '2.5V'        | '20%'       | 'DISCRETE' | 'CAPOSCONDIP560U 2.5V(20%.105C.5*8)SELASS'             | 'DIP'          | ''          | ''            | '20150310'
 '560UF'  | '2.5V'  | '20%'       | 'RDLF_SEL'  | 'EMPTY'    | 'CC7560JMD05'(!)             = ''              | ''                 | 'CC7560JMD05'                |'G_EC78_197_355'| '560UF'  | '2.5V'        | '20%'       | 'IO'       | 'CAPOSCONDIP560U 2.5V(20%.105C.5*8)SELASS'             | 'DIP'          | ''          | ''            | '20150310'
 '820UF'  | '2.5V'  | '20%'       | 'RDLF'      | 'ALUM'     | 'CC7820JMD12'(!)             = 'Potential'     | 'End of Life'      | 'CC7820JMD12'                |'EC98_248_354_EOL'| '820UF'  | '2.5V'        | '20%'       | 'DISCRETE' | 'CAP ELEC DIP 820U 2.5V(20% ESR6.5 6.3*9'              | 'DIP'          | ''          | ''            | '20150319'
 '820UF'  | '2.5V'  | '20%'       | 'RDLF'      | 'EMPTY'    | 'CC7820JMD12'(!)             = 'Potential'     | 'End of Life'      | 'CC7820JMD12'                |'EC98_248_354_EOL'| '820UF'  | '2.5V'        | '20%'       | 'IO'       | 'CAP ELEC DIP 820U 2.5V(20% ESR6.5 6.3*9'              | 'DIP'          | ''          | ''            | '20150319'
 '560UF'  | '6.3V'  | '20%'       | 'RDLF'      | 'ALUM'     | 'CC75601MD14'(!)             = 'Potential'     | 'End of Life'      | 'CC75601MD14'                |'EC98_248_354_EOL'| '560UF'  | '6.3V'        | '20%'       | 'DISCRETE' | 'CAP ELEC DIP 560U 6.3V(20% ESR6.5 6.3*9'              | 'DIP'          | ''          | ''            | '20150319'
 '560UF'  | '6.3V'  | '20%'       | 'RDLF'      | 'EMPTY'    | 'CC75601MD14'(!)             = 'Potential'     | 'End of Life'      | 'CC75601MD14'                |'EC98_248_354_EOL'| '560UF'  | '6.3V'        | '20%'       | 'IO'       | 'CAP ELEC DIP 560U 6.3V(20% ESR6.5 6.3*9'              | 'DIP'          | ''          | ''            | '20150319'
 '270UF'  | '16V'   | '20%'       | 'RDLF'      | 'ALUM'     | 'CC72703MD24'(!)             = 'Potential'     | 'End of Life'      | 'CC72703MD24'                |'EC98_248_354_EOL'| '270UF'  | '16V'         | '20%'       | 'DISCRETE' | 'CAP ELEC DIP 270U 16V(20% ESR9.5 6.3*9)'              | 'DIP'          | ''          | ''            | '20150319'
 '270UF'  | '16V'   | '20%'       | 'RDLF'      | 'EMPTY'    | 'CC72703MD24'(!)             = 'Potential'     | 'End of Life'      | 'CC72703MD24'                |'EC98_248_354_EOL'| '270UF'  | '16V'         | '20%'       | 'IO'       | 'CAP ELEC DIP 270U 16V(20% ESR9.5 6.3*9)'              | 'DIP'          | ''          | ''            | '20150319'
 '220UF'  | '100V'  | '20%'       | 'SMLF'      | 'ALUM'     | 'CC72208MZ00'(!)             = ''              | ''                 | 'CC72208MZ00'                |'EC248_630_847S'| '220UF'  | '100V'        | '20%'       | 'DISCRETE' | 'CAP ELEC SMD 220U 100V(+-20%,16*21.5)'                | 'SMT'          | ''          | ''            | '20150413'
 '220UF'  | '100V'  | '20%'       | 'SMLF'      | 'EMPTY'    | 'CC72208MZ00'(!)             = ''              | ''                 | 'CC72208MZ00'                |'EC248_630_847S'| '220UF'  | '100V'        | '20%'       | 'IO'       | 'CAP ELEC SMD 220U 100V(+-20%,16*21.5)'                | 'SMT'          | ''          | ''            | '20150413'
 '560UF'  | '10V'   | '20%'       | 'SMLF'      | 'ALUM'     | 'CC75602MZ00'(!)             = ''              | ''                 | 'CC75602MZ00'                |'EC181_394_496S'| '560UF'  | '10V'         | '20%'       | 'DISCRETE' | 'CAP SMD 560U 10V(20%,105C,10.3*10.3)'                 | 'SMT'          | ''          | ''            | '20150414'
 '560UF'  | '10V'   | '20%'       | 'SMLF'      | 'EMPTY'    | 'CC75602MZ00'(!)             = ''              | ''                 | 'CC75602MZ00'                |'EC181_394_496S'| '560UF'  | '10V'         | '20%'       | 'IO'       | 'CAP SMD 560U 10V(20%,105C,10.3*10.3)'                 | 'SMT'          | ''          | ''            | '20150414'
 '270UF'  | '16V'   | '20%'       | 'SMLF'      | 'ALUM'     | 'CC72703MZ02'(!)             = 'End of Design' | 'Comp-Approve'     | 'CC72703MZ02'                |'EC83_248_390S'| '270UF'  | '16V'         | '20%'       | 'DISCRETE' | 'CAP OSCON SMD 270U 16V(20%,105C,6.3*9.9)'             | 'SMT'          | ''          | ''            | '20150420'
 '270UF'  | '16V'   | '20%'       | 'SMLF'      | 'EMPTY'    | 'CC72703MZ02'(!)             = 'End of Design' | 'Comp-Approve'     | 'CC72703MZ02'                |'EC83_248_390S'| '270UF'  | '16V'         | '20%'       | 'IO'       | 'CAP OSCON SMD 270U 16V(20%,105C,6.3*9.9)'             | 'SMT'          | ''          | ''            | '20150420'
 '560UF'  | '2.5V'  | '20%'       | 'RDLF'      | 'ALUM'     | 'CC7560JMD13'(!)             = 'Potential'     | 'End of Life'      | 'CC7560JMD13'                |'EC78_197_355_EOL'| '560UF'  | '2.5V'        | '20%'       | 'DISCRETE' | 'CAP ELEC DIP 560U 2.5V(20% ESR6.5 5*9)'               | 'DIP'          | ''          | ''            | '20150504'
 '560UF'  | '2.5V'  | '20%'       | 'RDLF'      | 'EMPTY'    | 'CC7560JMD13'(!)             = 'Potential'     | 'End of Life'      | 'CC7560JMD13'                |'EC78_197_355_EOL'| '560UF'  | '2.5V'        | '20%'       | 'IO'       | 'CAP ELEC DIP 560U 2.5V(20% ESR6.5 5*9)'               | 'DIP'          | ''          | ''            | '20150504'
 '470UF'  | '2V'    | '20%'       | 'SMLF'      | 'POSCAP'   | 'CH747RM8822'(!)             = ''              | ''                 | 'CH747RM8822'                |'TAJ_DXC'| '470UF'  | '2V'          | '20%'       | 'DISCRETE' | 'CAP CHIP 470U 2V(+-20%,SPCAP,7343)MAT'                | 'SMT'          | ''          | ''            | '20150613'
 '470UF'  | '2V'    | '20%'       | 'SMLF'      | 'EMPTY'    | 'CH747RM8822'(!)             = ''              | ''                 | 'CH747RM8822'                |'TAJ_DXC'| '470UF'  | '2V'          | '20%'       | 'IO'       | 'CAP CHIP 470U 2V(+-20%,SPCAP,7343)MAT'                | 'SMT'          | ''          | ''            | '20150613'
 '100UF'  | '16V'   | '20%'       | 'RDLF'      | 'OSCON'    | 'CC71003MD14'(!)             = ''              | ''                 | 'CC71003MD14'                |'EC98_248_237'| '100UF'  | '16V'         | '20%'       | 'DISCRETE' | 'CAP OSCON DIP 100U 16V(20%,6.3*6)TOW'                 | 'DIP'          | ''          | ''            | '20150613'
 '100UF'  | '16V'   | '20%'       | 'RDLF'      | 'EMPTY'    | 'CC71003MD14'(!)             = ''              | ''                 | 'CC71003MD14'                |'EC98_248_237'| '100UF'  | '16V'         | '20%'       | 'IO'       | 'CAP OSCON DIP 100U 16V(20%,6.3*6)TOW'                 | 'DIP'          | ''          | ''            | '20150613'
 '100UF'  | '16V'   | '20%'       | 'RDLF'      | 'OSCON'    | 'SP_CC71003MD14'(!)          = ''              | ''                 | 'CC71003MD14'                |'G_EC98_248_237'| '100UF'  | '16V'         | '20%'       | 'DISCRETE' | 'CAP OSCON DIP 100U 16V(20%,6.3*6)TOW_FOR SEL'         | 'DIP'          | ''          | ''            | '20150613'
 '100UF'  | '16V'   | '20%'       | 'RDLF'      | 'EMPTY'    | 'SP_CC71003MD14'(!)          = ''              | ''                 | 'CC71003MD14'                |'G_EC98_248_237'| '100UF'  | '16V'         | '20%'       | 'IO'       | 'CAP OSCON DIP 100U 16V(20%,6.3*6)TOW_FOR SEL'         | 'DIP'          | ''          | ''            | '20150613'
 '100UF'  | '16V'   | '20%'       | 'SMLF'      | 'POSCAP'   | 'CH7103M8804'(!)             = 'End of Design' | 'Comp-Approve'     | 'CH7103M8804'                |'TAJ_D9'| '100UF'  | '16V'         | '20%'       | 'DISCRETE' | 'CAP CHIP 100UF 16V(20%,SPCAP,7343)MUR'                | 'SMT'          | ''          | ''            | '20150615'
 '100UF'  | '16V'   | '20%'       | 'SMLF'      | 'EMPTY'    | 'CH7103M8804'(!)             = 'End of Design' | 'Comp-Approve'     | 'CH7103M8804'                |'TAJ_D9'| '100UF'  | '16V'         | '20%'       | 'IO'       | 'CAP CHIP 100UF 16V(20%,SPCAP,7343)MUR'                | 'SMT'          | ''          | ''            | '20150615'
 '100UF'  | '100V'  | '20%'       | 'RDLF'      | 'ALUM'     | 'CC71008MD08'(!)             = ''              | ''                 | 'CC71008MD08'                |'EC197_394_787'| '100UF'  | '100V'        | '20%'       | 'DISCRETE' | 'CAP ELEC DIP 100U 100V(20%,10*20)RBN'                 | 'DIP'          | ''          | ''            | '20150615'
 '100UF'  | '100V'  | '20%'       | 'RDLF'      | 'EMPTY'    | 'CC71008MD08'(!)             = ''              | ''                 | 'CC71008MD08'                |'EC197_394_787'| '100UF'  | '100V'        | '20%'       | 'IO'       | 'CAP ELEC DIP 100U 100V(20%,10*20)RBN'                 | 'DIP'          | ''          | ''            | '20150615'
 '100UF'  | '100V'  | '20%'       | 'RDLF'      | 'ALUM'     | 'SP_CC71008MD08'(!)          = ''              | ''                 | 'CC71008MD08'                |'G_EC197_394_787'| '100UF'  | '100V'        | '20%'       | 'DISCRETE' | 'CAP ELEC DIP 100U 100V(20%,10*20)RBN_FOR SEL'         | 'DIP'          | ''          | ''            | '20150615'
 '100UF'  | '100V'  | '20%'       | 'RDLF'      | 'EMPTY'    | 'SP_CC71008MD08'(!)          = ''              | ''                 | 'CC71008MD08'                |'G_EC197_394_787'| '100UF'  | '100V'        | '20%'       | 'IO'       | 'CAP ELEC DIP 100U 100V(20%,10*20)RBN_FOR SEL'         | 'DIP'          | ''          | ''            | '20150615'
 '220UF'  | '10V'   | '20%'       | 'SMLF'      | 'POSCAP'   | 'CH7222MI801'(!)             = ''              | ''                 | 'CH7222MI801'                |'TAJ_D3L'| '220UF'  | '10V'         | '20%'       | 'DISCRETE' | 'CAP CHIP 220U 10V(20%,POSCAP,7343)SAY'                | 'SMT'          | ''          | ''            | '20150618'
 '220UF'  | '10V'   | '20%'       | 'SMLF'      | 'EMPTY'    | 'CH7222MI801'(!)             = ''              | ''                 | 'CH7222MI801'                |'TAJ_D3L'| '220UF'  | '10V'         | '20%'       | 'IO'       | 'CAP CHIP 220U 10V(20%,POSCAP,7343)SAY'                | 'SMT'          | ''          | ''            | '20150618'
 '47UF'   | '16V'   | '20%'       | 'SMLF'      | 'POSCAP'   | 'CH6473M8802'(!)             = ''              | 'Comp-Release Qty' | 'CH6473M8802'                | 'TAJ_DXC'                  | '47UF'   | '16V'         | '20%'       | 'DISCRETE' | 'CAP CHIP 47U 16V(+-20%,ESR=40,7343)SPCAP'             | 'SMT'          | ''          | ''            | '20150709'
 '47UF'   | '16V'   | '20%'       | 'SMLF'      | 'EMPTY'    | 'CH6473M8802'(!)             = ''              | 'Comp-Release Qty' | 'CH6473M8802'                | 'TAJ_DXC'                  | '47UF'   | '16V'         | '20%'       | 'IO'       | 'CAP CHIP 47U 16V(+-20%,ESR=40,7343)SPCAP'             | 'SMT'          | ''          | ''            | '20150709'
 '0.011F' | '3.3V'  | '18%'       | 'SMLF'      | ''         | 'CC9110KTZ00'(!)             = ''              | ''                 | 'CC9110KTZ00'                |'EC1210'| '0.011F' | '3.3V'        | '18%'       | 'DISCRETE' | 'CAP ELEC SMD 0.011F 3.3V(18%,3.2*2.5)'                | 'SMT'          | ''          | ''            | '20150728'
 '0.011F' | '3.3V'  | '18%'       | 'SMLF'      | 'EMPTY'    | 'CC9110KTZ00'(!)             = ''              | ''                 | 'CC9110KTZ00'                |'EC1210'| '0.011F' | '3.3V'        | '18%'       | 'IO'       | 'CAP ELEC SMD 0.011F 3.3V(18%,3.2*2.5)'                | 'SMT'          | ''          | ''            | '20150728'
 '100UF'  | '16V'   | '20%'       | 'SMLF'      | 'ALUM'     | 'CC71003MZ26'(!)             = ''              | ''                 | 'CC71003MZ26'                |'EC56_197_229S'| '100UF'  | '16V'         | '20%'       | 'DISCRETE' | 'CAP OSCON SMD 100U 16V(20%,ESR26,5*5.8)'              | 'SMT'          | ''          | ''            | '20150807'
 '100UF'  | '16V'   | '20%'       | 'SMLF'      | 'EMPTY'    | 'CC71003MZ26'(!)             = ''              | ''                 | 'CC71003MZ26'                |'EC56_197_229S'| '100UF'  | '16V'         | '20%'       | 'IO'       | 'CAP OSCON SMD 100U 16V(20%,ESR26,5*5.8)'              | 'SMT'          | ''          | ''            | '20150807'
 '180UF'  | '16V'   | '20%'       | 'SMLF'      | 'ALUM'     | 'CC71803MZ06'(!)             = ''              | ''                 | 'CC71803MZ06'                |'EC83_248_229S'| '180UF'  | '16V'         | '20%'       | 'DISCRETE' | 'CAP OSCON SMD 180U 16V(20%,ESR21,6.3*5.8'             | 'SMT'          | ''          | ''            | '20150807'
 '180UF'  | '16V'   | '20%'       | 'SMLF'      | 'EMPTY'    | 'CC71803MZ06'(!)             = ''              | ''                 | 'CC71803MZ06'                |'EC83_248_229S'| '180UF'  | '16V'         | '20%'       | 'IO'       | 'CAP OSCON SMD 180U 16V(20%,ESR21,6.3*5.8'             | 'SMT'          | ''          | ''            | '20150807'
 '560UF'  | '2.5V'  | '20%'       | 'RDLF'      | 'OSCON'    | 'CC7560JMD14'(!)             = 'Potential'     | 'End of Life'      | 'CC7560JMD14'                |'EC78_197_315_EOL'| '560UF'  | '2.5V'        | '20%'       | 'DISCRETE' | 'CAP OSCON DIP 560U 2.5V(20%,5*8)TOW'                  | 'DIP'          | ''          | ''            | '20150810'
 '560UF'  | '2.5V'  | '20%'       | 'RDLF'      | 'EMPTY'    | 'CC7560JMD14'(!)             = 'Potential'     | 'End of Life'      | 'CC7560JMD14'                |'EC78_197_315_EOL'| '560UF'  | '2.5V'        | '20%'       | 'IO'       | 'CAP OSCON DIP 560U 2.5V(20%,5*8)TOW'                  | 'DIP'          | ''          | ''            | '20150810'
 '560UF'  | '2.5V'  | '20%'       | 'RDLF'      | 'OSCON'    | 'SP_CC7560JMD14'(!)          = 'Potential'     | 'End of Life'      | 'CC7560JMD14'                |'G_EC78_197_315_EOL'| '560UF'  | '2.5V'        | '20%'       | 'DISCRETE' | 'CAP OSCON DIP 560U 2.5V(20%,5*8)TOW_FOR SEL'          | 'DIP'          | ''          | ''            | '20150810'
 '560UF'  | '2.5V'  | '20%'       | 'RDLF'      | 'EMPTY'    | 'SP_CC7560JMD14'(!)          = 'Potential'     | 'End of Life'      | 'CC7560JMD14'                |'G_EC78_197_315_EOL'| '560UF'  | '2.5V'        | '20%'       | 'IO'       | 'CAP OSCON DIP 560U 2.5V(20%,5*8)TOW_FOR SEL'          | 'DIP'          | ''          | ''            | '20150810'
 '100UF'  | '16V'   | '20%'       | 'SMLF'      | 'OSCON'    | 'CC71003MZ28'(!)             = ''              | ''                 | 'CC71003MZ28'                |'EC83_248_232S'| '100UF'  | '16V'         | '20%'       | 'DISCRETE' | 'CAP OSCON SMD 100U 16V(20%,6.3*5.9)SAY'               | 'SMT'          | ''          | ''            | '20150826'
 '100UF'  | '16V'   | '20%'       | 'SMLF'      | 'EMPTY'    | 'CC71003MZ28'(!)             = ''              | ''                 | 'CC71003MZ28'                |'EC83_248_232S'| '100UF'  | '16V'         | '20%'       | 'IO'       | 'CAP OSCON SMD 100U 16V(20%,6.3*5.9)SAY'               | 'SMT'          | ''          | ''            | '20150826'
 '390UF'  | '2.5V'  | '20%'       | 'SMLF'      | 'OSCON'    | 'CC7390JMZ11'(!)             = ''              | ''                 | 'CC7390JMZ11'                |'EC56_197_233S'| '390UF'  | '2.5V'        | '20%'       | 'DISCRETE' | 'CAP OSCON SMD 390U 2.5V(20%,5*5.9)SAY'                | 'SMT'          | ''          | ''            | '20150826'
 '390UF'  | '2.5V'  | '20%'       | 'SMLF'      | 'EMPTY'    | 'CC7390JMZ11'(!)             = ''              | ''                 | 'CC7390JMZ11'                |'EC56_197_233S'| '390UF'  | '2.5V'        | '20%'       | 'IO'       | 'CAP OSCON SMD 390U 2.5V(20%,5*5.9)SAY'                | 'SMT'          | ''          | ''            | '20150826'
 '10UF'   | '100V'  | '20%'       | 'SMLF'      | 'ALUM'     | 'CC61008MZ02'(!)             = ''              | ''                 | 'CC61008MZ02'                |'EC75_248_303S_EOL'| '10UF'   | '100V'        | '20%'       | 'DISCRETE' | 'CAP ELEC 10U 100V(+-20%,105C,6.3*7.7)NPN'             | 'SMT'          | ''          | ''            | '20151022'
 '10UF'   | '100V'  | '20%'       | 'SMLF'      | 'EMPTY'    | 'CC61008MZ02'(!)             = ''              | ''                 | 'CC61008MZ02'                |'EC75_248_303S_EOL'| '10UF'   | '100V'        | '20%'       | 'IO'       | 'CAP ELEC 10U 100V(+-20%,105C,6.3*7.7)NPN'             | 'SMT'          | ''          | ''            | '20151022'
 '330UF'  | '16V'   | '20%'       | 'SMLF'      | 'ALUM'     | 'CC73303MZ01'(!)             = 'End of Design' | 'Comp-Approve'     | 'CC73303MZ01'                |'EC178_394_394S'| '330UF'  | '16V'         | '20%'       | 'DISCRETE' | 'CAP OSCON 330U 16V (20%,105C,10*10)NPN'               | 'SMT'          | ''          | ''            | '20151022'
 '330UF'  | '16V'   | '20%'       | 'SMLF'      | 'EMPTY'    | 'CC73303MZ01'(!)             = 'End of Design' | 'Comp-Approve'     | 'CC73303MZ01'                |'EC178_394_394S'| '330UF'  | '16V'         | '20%'       | 'IO'       | 'CAP OSCON 330U 16V (20%,105C,10*10)NPN'               | 'SMT'          | ''          | ''            | '20151022'
 '100UF'  | '16V'   | '20%'       | 'SMLF'      | 'ALUM'     | 'CC71003MZ29'(!)             = ''              | ''                 | 'CC71003MZ29'                |'EC75_248_229SXA'| '100UF'  | '16V'         | '20%'       | 'DISCRETE' | 'CAP OSCON SMD 100U 16V(20%,6.3*5.8)NPN'               | 'SMT'          | ''          | ''            | '20151022'
 '100UF'  | '16V'   | '20%'       | 'SMLF'      | 'EMPTY'    | 'CC71003MZ29'(!)             = ''              | ''                 | 'CC71003MZ29'                |'EC75_248_229SXA'| '100UF'  | '16V'         | '20%'       | 'IO'       | 'CAP OSCON SMD 100U 16V(20%,6.3*5.8)NPN'               | 'SMT'          | ''          | ''            | '20151022'
 '100UF'  | '16V'   | '20%'       | 'THLF'      | 'ALUM'     | 'CC71003MD17'(!)             = ''              | ''                 | 'CC71003MD17'                |'EC2-5_6-8_6'| '100UF'  | '16V'         | '20%'       | 'DISCRETE' | 'CAP OSCON DIP 100U 16V(20%,6.3*6)NPN'                 | 'DIP'          | ''          | ''            | '20151022'
 '100UF'  | '16V'   | '20%'       | 'THLF'      | 'EMPTY'    | 'CC71003MD17'(!)             = ''              | ''                 | 'CC71003MD17'                |'EC2-5_6-8_6'| '100UF'  | '16V'         | '20%'       | 'IO'       | 'CAP OSCON DIP 100U 16V(20%,6.3*6)NPN'                 | 'DIP'          | ''          | ''            | '20151022'
 '100UF'  | '20V'   | '20%'       | 'SMLF'      | 'POSCAP'   | 'CH710BMI803'(!)             = ''              | ''                 | 'CH710BMI803'                |'TAJ_D3L'| '100UF'  | '20V'         | '20%'       | 'DISCRETE' | 'CAP 100U 20V(20%,POSCAP,ESR55,7343)SAY'               | 'SMT'          | ''          | ''            | '20151022'
 '100UF'  | '20V'   | '20%'       | 'SMLF'      | 'EMPTY'    | 'CH710BMI803'(!)             = ''              | ''                 | 'CH710BMI803'                |'TAJ_D3L'| '100UF'  | '20V'         | '20%'       | 'IO'       | 'CAP 100U 20V(20%,POSCAP,ESR55,7343)SAY'               | 'SMT'          | ''          | ''            | '20151022'
 '180UF'  | '20V'   | '20%'       | 'SMLF'      | 'ALUM'     | 'CC7180HMZ00'(!)             = ''              | ''                 | 'CC7180HMZ00'                |'EC126_315_272S'| '180UF'  | '20V'         | '20%'       | 'DISCRETE' | 'CAP OS-CON 180U 20V(20%.105C.8*6.9)SMD'               | 'SMT'          | ''          | ''            | '20151123'
 '180UF'  | '20V'   | '20%'       | 'SMLF'      | 'EMPTY'    | 'CC7180HMZ00'(!)             = ''              | ''                 | 'CC7180HMZ00'                |'EC126_315_272S'| '180UF'  | '20V'         | '20%'       | 'IO'       | 'CAP OS-CON 180U 20V(20%.105C.8*6.9)SMD'               | 'SMT'          | ''          | ''            | '20151123'
 '330UF'  | '6.3V'  | '20%'       | 'SMLF'      | 'TANT'     | 'CH7331M8805'(!)             = 'End of Design' | 'Comp-Approve'     | 'CH7331M8805'                |'TAJ_D3L'| '330UF'  | '6.3V'        | '20%'       | 'DISCRETE' | 'CAP CHIP 330U 6.3V 20% ESR10(7343)POSCAP'             | 'SMT'          | ''          | ''            | '20151123'
 '330UF'  | '6.3V'  | '20%'       | 'SMLF'      | 'EMPTY'    | 'CH7331M8805'(!)             = 'End of Design' | 'Comp-Approve'     | 'CH7331M8805'                |'TAJ_D3L'| '330UF'  | '6.3V'        | '20%'       | 'IO'       | 'CAP CHIP 330U 6.3V 20% ESR10(7343)POSCAP'             | 'SMT'          | ''          | ''            | '20151123'
 '330UF'  | '6.3V'  | '20%'       | 'SMLF'      | 'TANT'     | 'CH7331M8819'(!)             = ''              | ''                 | 'CH7331M8819'                |'TAJ_D3L'| '330UF'  | '6.3V'        | '20%'       | 'DISCRETE' | 'CAP CHIP 330U 6.3V(+-20%,POSCAP,7343)'                | 'SMT'          | ''          | ''            | '20151123'
 '330UF'  | '6.3V'  | '20%'       | 'SMLF'      | 'EMPTY'    | 'CH7331M8819'(!)             = ''              | ''                 | 'CH7331M8819'                |'TAJ_D3L'| '330UF'  | '6.3V'        | '20%'       | 'IO'       | 'CAP CHIP 330U 6.3V(+-20%,POSCAP,7343)'                | 'SMT'          | ''          | ''            | '20151123'
 '270UF'  | '16V'   | '20%'       | 'RDLF'      | 'OSCON'    | 'SP_CC72703MD26_1'(!)        = ''              | ''                 | 'CC72703MD26'                |'G_EC138_315_315_UH3M'| '270UF'  | '16V'         | '20%'       | 'DISCRETE' | 'CAP OSCON DIP 270U 16V(+-20%,8*8)TOW_FOR SEL_UH3M'    | 'DIP'          | ''          | ''            | '20151215'
 '270UF'  | '16V'   | '20%'       | 'RDLF'      | 'EMPTY'    | 'SP_CC72703MD26_1'(!)        = ''              | ''                 | 'CC72703MD26'                |'G_EC138_315_315_UH3M'| '270UF'  | '16V'         | '20%'       | 'IO'       | 'CAP OSCON DIP 270U 16V(+-20%,8*8)TOW_FOR SEL_UH3M'    | 'DIP'          | ''          | ''            | '20151215'
 '100UF'  | '100V'  | '20%'       | 'RDLF'      | 'ALUM'     | 'SP_CC71008MD07_1'(!)        = ''              | ''                 | 'CC71008MD07'                |'G_EC197_394_787_UH3M'| '100UF'  | '100V'        | '20%'       | 'DISCRETE' | 'CAP ELEC DIP 100U 100V(20%,10*20)NPN_FOR SEL_UH3M'    | 'DIP'          | ''          | ''            | '20151215'
 '100UF'  | '100V'  | '20%'       | 'RDLF'      | 'EMPTY'    | 'SP_CC71008MD07_1'(!)        = ''              | ''                 | 'CC71008MD07'                |'G_EC197_394_787_UH3M'| '100UF'  | '100V'        | '20%'       | 'IO'       | 'CAP ELEC DIP 100U 100V(20%,10*20)NPN_FOR SEL_UH3M'    | 'DIP'          | ''          | ''            | '20151215'
 '560UF'  | '6.3V'  | '20%'       | 'RDLF'      | 'OSCON'    | 'SP_CC75601MD15_1'(!)        = ''              | ''                 | 'CC75601MD15'                |'G_EC98_248_315_UH3M'| '560UF'  | '6.3V'        | '20%'       | 'DISCRETE' | 'CAP OSCON DIP 560U 6.3V(+-20%,6.3*8)TOW_FOR SEL_UH3M' | 'DIP'          | ''          | ''            | '20151215'
 '560UF'  | '6.3V'  | '20%'       | 'RDLF'      | 'EMPTY'    | 'SP_CC75601MD15_1'(!)        = ''              | ''                 | 'CC75601MD15'                |'G_EC98_248_315_UH3M'| '560UF'  | '6.3V'        | '20%'       | 'IO'       | 'CAP OSCON DIP 560U 6.3V(+-20%,6.3*8)TOW_FOR SEL_UH3M' | 'DIP'          | ''          | ''            | '20151215'
 '100UF'  | '16V'   | '20%'       | 'RDLF'      | 'ALUM'     | 'SP_CC71003MD17'(!)          = ''              | ''                 | 'CC71003MD17'                |'G_EC98_248_237_UH3M'| '100UF'  | '16V'         | '20%'       | 'DISCRETE' | 'CAP OSCON DIP 100U 16V(20%,6.3*6)NPN_FOR SEL_UH3M'    | 'DIP'          | ''          | ''            | '20151215'
 '100UF'  | '16V'   | '20%'       | 'RDLF'      | 'EMPTY'    | 'SP_CC71003MD17'(!)          = ''              | ''                 | 'CC71003MD17'                |'G_EC98_248_237_UH3M'| '100UF'  | '16V'         | '20%'       | 'IO'       | 'CAP OSCON DIP 100U 16V(20%,6.3*6)NPN_FOR SEL_UH3M'    | 'DIP'          | ''          | ''            | '20151215'
 '560UF'  | '6.3V'  | '20%'       | 'RDLF'      | 'OSCON'    | 'CC75601MD15'(!)             = ''              | ''                 | 'CC75601MD15'                |'EC98_248_315'| '560UF'  | '6.3V'        | '20%'       | 'DISCRETE' | 'CAP OSCON DIP 560U 6.3V(+-20%,6.3*8)TOW'              | 'DIP'          | ''          | ''            | '20151215'
 '560UF'  | '6.3V'  | '20%'       | 'RDLF'      | 'EMPTY'    | 'CC75601MD15'(!)             = ''              | ''                 | 'CC75601MD15'                |'EC98_248_315'| '560UF'  | '6.3V'        | '20%'       | 'IO'       | 'CAP OSCON DIP 560U 6.3V(+-20%,6.3*8)TOW'              | 'DIP'          | ''          | ''            | '20151215'
 '560UF'  | '6.3V'  | '20%'       | 'RDLF'      | 'OSCON'    | 'SP_CC75601MD15'(!)          = ''              | ''                 | 'CC75601MD15'                |'G_EC98_248_315'| '560UF'  | '6.3V'        | '20%'       | 'DISCRETE' | 'CAP OSCON DIP 560U 6.3V(+-20%,6.3*8)TOW_FOR SEL'      | 'DIP'          | ''          | ''            | '20151215'
 '560UF'  | '6.3V'  | '20%'       | 'RDLF'      | 'EMPTY'    | 'SP_CC75601MD15'(!)          = ''              | ''                 | 'CC75601MD15'                |'G_EC98_248_315'| '560UF'  | '6.3V'        | '20%'       | 'IO'       | 'CAP OSCON DIP 560U 6.3V(+-20%,6.3*8)TOW_FOR SEL'      | 'DIP'          | ''          | ''            | '20151215'
 '270UF'  | '16V'   | '20%'       | 'RDLF'      | 'OSCON'    | 'CC72703MD26'(!)             = ''              | ''                 | 'CC72703MD26'                |'EC138_315_315'| '270UF'  | '16V'         | '20%'       | 'DISCRETE' | 'CAP OSCON DIP 270U 16V(+-20%,8*8)TOW'                 | 'DIP'          | ''          | ''            | '20151215'
 '270UF'  | '16V'   | '20%'       | 'RDLF'      | 'EMPTY'    | 'CC72703MD26'(!)             = ''              | ''                 | 'CC72703MD26'                |'EC138_315_315'| '270UF'  | '16V'         | '20%'       | 'IO'       | 'CAP OSCON DIP 270U 16V(+-20%,8*8)TOW'                 | 'DIP'          | ''          | ''            | '20151215'
 '270UF'  | '16V'   | '20%'       | 'RDLF'      | 'OSCON'    | 'SP_CC72703MD26'(!)          = ''              | ''                 | 'CC72703MD26'                |'G_EC138_315_315'| '270UF'  | '16V'         | '20%'       | 'DISCRETE' | 'CAP OSCON DIP 270U 16V(+-20%,8*8)TOW_FOR SEL'         | 'DIP'          | ''          | ''            | '20151215'
 '270UF'  | '16V'   | '20%'       | 'RDLF'      | 'EMPTY'    | 'SP_CC72703MD26'(!)          = ''              | ''                 | 'CC72703MD26'                |'G_EC138_315_315'| '270UF'  | '16V'         | '20%'       | 'IO'       | 'CAP OSCON DIP 270U 16V(+-20%,8*8)TOW_FOR SEL'         | 'DIP'          | ''          | ''            | '20151215'
 '220UF'  | '6.3V'  | '20%'       | 'SMLF'      | 'ALUM'     | 'CC72201MZ27'(!)             = ''              | ''                 | 'CC72201MZ27'                |'EC56_197_233S'| '220UF'  | '6.3V'        | '20%'       | 'DISCRETE' | 'CAP OSCON SMD 220U 6.3V(20%,5*5.8)SAY'                | 'SMT'          | ''          | ''            | '20160122'
 '220UF'  | '6.3V'  | '20%'       | 'SMLF'      | 'EMPTY'    | 'CC72201MZ27'(!)             = ''              | ''                 | 'CC72201MZ27'                |'EC56_197_233S'| '220UF'  | '6.3V'        | '20%'       | 'IO'       | 'CAP OSCON SMD 220U 6.3V(20%,5*5.8)SAY'                | 'SMT'          | ''          | ''            | '20160122'
 '100UF'  | '16V'   | '20%'       | 'SMLF'      | 'POSCAP'   | 'CH7103MI803'(!)             = 'End of Design' | 'Comp-Approve'     | 'CH7103MI803'                |'TAJ_7343-20'| '100UF'  | '16V'         | '20%'       | 'DISCRETE' | 'CAP CHIP 100UF 16V(20%,POSCAP,7343)KEM'               | 'SMT'          | ''          | ''            | '20160523'
 '100UF'  | '16V'   | '20%'       | 'SMLF'      | 'EMPTY'    | 'CH7103MI803'(!)             = 'End of Design' | 'Comp-Approve'     | 'CH7103MI803'                |'TAJ_7343-20'| '100UF'  | '16V'         | '20%'       | 'IO'       | 'CAP CHIP 100UF 16V(20%,POSCAP,7343)KEM'               | 'SMT'          | ''          | ''            | '20160523'
 '220UF'  | '16V'   | '20%'       | 'SMLF'      | 'ALUM'     | 'CC72203MZ35'(!)             = 'End of Design' | 'Comp-Approve'     | 'CC72203MZ35'                |'EC87_248_303S'| '220UF'  | '16V'         | '20%'       | 'DISCRETE' | 'CAP SMD 220U 16V(+-20%.105C.6.3*7.7)'                 | 'SMT'          | ''          | ''            | '20160526'
 '220UF'  | '16V'   | '20%'       | 'SMLF'      | 'EMPTY'    | 'CC72203MZ35'(!)             = 'End of Design' | 'Comp-Approve'     | 'CC72203MZ35'                |'EC87_248_303S'| '220UF'  | '16V'         | '20%'       | 'IO'       | 'CAP SMD 220U 16V(+-20%.105C.6.3*7.7)'                 | 'SMT'          | ''          | ''            | '20160526'
 '820UF'  | '16V'   | '20%'       | 'RDLF'      | 'OSCON'    | 'CC78203MD04'(!)             = ''              | ''                 | 'CC78203MD04'                |'EC197_394_473'| '820UF'  | '16V'         | '20%'       | 'DISCRETE' | 'CAP OSCON DIP 820U 16V(20%,ESR10,10*12)'              | 'DIP'          | ''          | ''            | '20160725'
 '820UF'  | '16V'   | '20%'       | 'RDLF'      | 'EMPTY'    | 'CC78203MD04'(!)             = ''              | ''                 | 'CC78203MD04'                |'EC197_394_473'| '820UF'  | '16V'         | '20%'       | 'IO'       | 'CAP OSCON DIP 820U 16V(20%,ESR10,10*12)'              | 'DIP'          | ''          | ''            | '20160725'
 '33UF'   | '16V'   | '20%'       | 'SMLF'      | 'POSCAP'   | 'CH6333MI606'(!)             = 'End of Design' | 'Comp-Approve'     | 'CH6333MI606'                |'TAJ_B2XA'| '33UF'   | '16V'         | '20%'       | 'DISCRETE' | 'CAP CHIP 33U 16V(20%,POSCAP,ESR70,3528)'              | 'SMT'          | ''          | ''            | '20160923'
 '33UF'   | '16V'   | '20%'       | 'SMLF'      | 'EMPTY'    | 'CH6333MI606'(!)             = 'End of Design' | 'Comp-Approve'     | 'CH6333MI606'                |'TAJ_B2XA'| '33UF'   | '16V'         | '20%'       | 'IO'       | 'CAP CHIP 33U 16V(20%,POSCAP,ESR70,3528)'              | 'SMT'          | ''          | ''            | '20160923'
 '330UF'  | '6.3V'  | '20%'       | 'SMLF'      | 'TANT'     | 'CH7331M8869'(!)             = 'End of Design' | 'Comp-Approve'     | 'CH7331M8869'                |'TAJ_DXB'| '330UF'  | '6.3V'        | '20%'       | 'DISCRETE' | 'CAP CHIP 330U 6.3V(20%,ESR15,7343,H2.8)'              | 'SMT'          | ''          | ''            | '20161020'
 '330UF'  | '6.3V'  | '20%'       | 'SMLF'      | 'EMPTY'    | 'CH7331M8869'(!)             = 'End of Design' | 'Comp-Approve'     | 'CH7331M8869'                |'TAJ_DXB'| '330UF'  | '6.3V'        | '20%'       | 'IO'       | 'CAP CHIP 330U 6.3V(20%,ESR15,7343,H2.8)'              | 'SMT'          | ''          | ''            | '20161020'
 '3900UF' | '16V'   | '20%'       | 'THLF'      | ''         | 'CC83903MD00'(!)             = ''              | ''                 | 'CC83903MD00'                |'EC197_493_1378'| '3900UF' | '16V'         | '20%'       | 'DISCRETE' | 'CAP ELEC DIP 3900U 16V(20%,105C,12.5*35)'             | 'DIP'          | ''          | ''            | '20161020'
 '3900UF' | '16V'   | '20%'       | 'THLF'      | 'EMPTY'    | 'CC83903MD00'(!)             = ''              | ''                 | 'CC83903MD00'                |'EC197_493_1378'| '3900UF' | '16V'         | '20%'       | 'IO'       | 'CAP ELEC DIP 3900U 16V(20%,105C,12.5*35)'             | 'DIP'          | ''          | ''            | '20161020'
 '3900UF' | '16V'   | '20%'       | 'THLF'      | ''         | 'CC83903MD01'(!)             = ''              | ''                 | 'CC83903MD01'                |'EC197_493_1240'| '3900UF' | '16V'         | '20%'       | 'DISCRETE' | 'CAP ELEC DIP 3900U 16V(20%,12.5*31.5)'                | 'DIP'          | ''          | ''            | '20161021'
 '3900UF' | '16V'   | '20%'       | 'THLF'      | 'EMPTY'    | 'CC83903MD01'(!)             = ''              | ''                 | 'CC83903MD01'                |'EC197_493_1240'| '3900UF' | '16V'         | '20%'       | 'IO'       | 'CAP ELEC DIP 3900U 16V(20%,12.5*31.5)'                | 'DIP'          | ''          | ''            | '20161021'
 '4700UF' | '16V'   | '20%'       | 'THLF'      | ''         | 'CC84703MD00'(!)             = ''              | ''                 | 'CC84703MD00'                |'EC197_493_1398'| '4700UF' | '16V'         | '20%'       | 'DISCRETE' | 'CAP ELEC DIP 4700U 16V(20%,12.5*35.5)'                | 'DIP'          | ''          | ''            | '20161028'
 '4700UF' | '16V'   | '20%'       | 'THLF'      | 'EMPTY'    | 'CC84703MD00'(!)             = ''              | ''                 | 'CC84703MD00'                |'EC197_493_1398'| '4700UF' | '16V'         | '20%'       | 'IO'       | 'CAP ELEC DIP 4700U 16V(20%,12.5*35.5)'                | 'DIP'          | ''          | ''            | '20161028'
 '1000UF' | '16V'   | '20%'       | 'THLF'      | 'OSCON'    | 'CC81003MD10'(!)             = ''              | ''                 | 'CC81003MD10'                |'EC5_10-5_13'| '1000UF' | '16V'         | '20%'       | 'DISCRETE' | 'CAP OSCON DIP 1000U 16V(20%,10*11.5)'                 | 'DIP'          | ''          | ''            | '20170405'
 '1000UF' | '16V'   | '20%'       | 'THLF'      | 'EMPTY'    | 'CC81003MD10'(!)             = ''              | ''                 | 'CC81003MD10'                |'EC5_10-5_13'| '1000UF' | '16V'         | '20%'       | 'IO'       | 'CAP OSCON DIP 1000U 16V(20%,10*11.5)'                 | 'DIP'          | ''          | ''            | '20170405'
 '220UF'  | '6.3V'  | '20%'       | 'SMLF'      | 'ALUM'     | 'CC72201MZ28'(!)             = ''              | ''                 | 'CC72201MZ28'                |'EC56_197_229SXA'| '220UF'  | '6.3V'        | '20%'       | 'DISCRETE' | 'CAP OSCON SMD 220U 6.3V(20%,5*5.8)NPN'                | 'SMT'          | ''          | ''            | '20170503'
 '220UF'  | '6.3V'  | '20%'       | 'SMLF'      | 'EMPTY'    | 'CC72201MZ28'(!)             = ''              | ''                 | 'CC72201MZ28'                |'EC56_197_229SXA'| '220UF'  | '6.3V'        | '20%'       | 'IO'       | 'CAP OSCON SMD 220U 6.3V(20%,5*5.8)NPN'                | 'SMT'          | ''          | ''            | '20170503'
 '390UF'  | '2.5V'  | '20%'       | 'SMLF'      | 'ALUM'     | 'CC7390JMZ13'(!)             = ''              | ''                 | 'CC7390JMZ13'                |'EC56_197_229SXA'| '390UF'  | '2.5V'        | '20%'       | 'DISCRETE' | 'CAP OSCON SMD 390U 2.5V(20%,5*5.8)NPN'                | 'SMT'          | ''          | ''            | '20170503'
 '390UF'  | '2.5V'  | '20%'       | 'SMLF'      | 'EMPTY'    | 'CC7390JMZ13'(!)             = ''              | ''                 | 'CC7390JMZ13'                |'EC56_197_229SXA'| '390UF'  | '2.5V'        | '20%'       | 'IO'       | 'CAP OSCON SMD 390U 2.5V(20%,5*5.8)NPN'                | 'SMT'          | ''          | ''            | '20170503'
 '180UF'  | '16V'   | '20%'       | 'SMLF'      | 'ALUM'     | 'CC71803MZ07'(!)             = ''              | ''                 | 'CC71803MZ07'                |'EC83_248_233S'| '180UF'  | '16V'         | '20%'       | 'DISCRETE' | 'CAP OSCON SMD 180U 16V(20%,6.3*5.9)SAY'               | 'SMT'          | ''          | ''            | '20170505'
 '180UF'  | '16V'   | '20%'       | 'SMLF'      | 'EMPTY'    | 'CC71803MZ07'(!)             = ''              | ''                 | 'CC71803MZ07'                |'EC83_248_233S'| '180UF'  | '16V'         | '20%'       | 'IO'       | 'CAP OSCON SMD 180U 16V(20%,6.3*5.9)SAY'               | 'SMT'          | ''          | ''            | '20170505'
 '180UF'  | '16V'   | '20%'       | 'SMLF'      | 'ALUM'     | 'CC71803MZ08'(!)             = ''              | ''                 | 'CC71803MZ08'                |'EC75_248_229S'| '180UF'  | '16V'         | '20%'       | 'DISCRETE' | 'CAP OSCON SMD 180U 16V(20%,6.3*5.8)NPN'               | 'SMT'          | ''          | ''            | '20170505'
 '180UF'  | '16V'   | '20%'       | 'SMLF'      | 'EMPTY'    | 'CC71803MZ08'(!)             = ''              | ''                 | 'CC71803MZ08'                |'EC75_248_229S'| '180UF'  | '16V'         | '20%'       | 'IO'       | 'CAP OSCON SMD 180U 16V(20%,6.3*5.8)NPN'               | 'SMT'          | ''          | ''            | '20170505'
 '100UF'  | '16V'   | '20%'       | 'THLF'      | 'OSCON'    | 'CC71003MD19'(!)             = 'End of Design' | 'Comp-Approve'     | 'CC71003MD19'                |'EC98_248_237'| '100UF'  | '16V'         | '20%'       | 'DISCRETE' | 'CAP OSCON DIP 100U 16V(20%,6.3*6)SAY'                 | 'DIP'          | ''          | ''            | '20170505'
 '100UF'  | '16V'   | '20%'       | 'THLF'      | 'EMPTY'    | 'CC71003MD19'(!)             = 'End of Design' | 'Comp-Approve'     | 'CC71003MD19'                |'EC98_248_237'| '100UF'  | '16V'         | '20%'       | 'IO'       | 'CAP OSCON DIP 100U 16V(20%,6.3*6)SAY'                 | 'DIP'          | ''          | ''            | '20170505'
 '560UF'  | '2.5V'  | '20%'       | 'THLF'      | 'OSCON'    | 'CC7560JMD15'(!)             = ''              | ''                 | 'CC7560JMD15'                |'EC2_5-5_9'| '560UF'  | '2.5V'        | '20%'       | 'DISCRETE' | 'CAP OSCON DIP 560U 2.5V(20%,105C,5*8)NPN'             | 'DIP'          | ''          | ''            | '20170519'
 '560UF'  | '2.5V'  | '20%'       | 'THLF'      | 'EMPTY'    | 'CC7560JMD15'(!)             = ''              | ''                 | 'CC7560JMD15'                |'EC2_5-5_9'| '560UF'  | '2.5V'        | '20%'       | 'IO'       | 'CAP OSCON DIP 560U 2.5V(20%,105C,5*8)NPN'             | 'DIP'          | ''          | ''            | '20170519'
 '560UF'  | '2.5V'  | '20%'       | 'THLF'      | 'OSCON'    | 'SP_CC7560JMD15'(!)          = ''              | ''                 | 'CC7560JMD15'                |'G_EC2_5-5_9'| '560UF'  | '2.5V'        | '20%'       | 'DISCRETE' | 'CAP OSCON DIP 560U 2.5V(20%,105C,5*8)NPN_FOR SEL'     | 'DIP'          | ''          | ''            | '20170519'
 '560UF'  | '2.5V'  | '20%'       | 'THLF'      | 'EMPTY'    | 'SP_CC7560JMD15'(!)          = ''              | ''                 | 'CC7560JMD15'                |'G_EC2_5-5_9'| '560UF'  | '2.5V'        | '20%'       | 'IO'       | 'CAP OSCON DIP 560U 2.5V(20%,105C,5*8)NPN_FOR SEL'     | 'DIP'          | ''          | ''            | '20170519'
 '220UF'  | '4V'    | '20%'       | 'SMLF'      | 'TANT'     | 'CH122KM8800'(!)             = ''              | ''                 | 'CH122KM8800'                |'TAJ_SX'| '220UF'  | '4V'          | '20%'       | 'DISCRETE' | 'CAP CHIP 220U 4V(+-20%,SPCAP,7343)'                   | 'SMT'          | ''          | ''            | '20170602'
 '220UF'  | '4V'    | '20%'       | 'SMLF'      | 'EMPTY'    | 'CH122KM8800'(!)             = ''              | ''                 | 'CH122KM8800'                |'TAJ_SX'| '220UF'  | '4V'          | '20%'       | 'IO'       | 'CAP CHIP 220U 4V(+-20%,SPCAP,7343)'                   | 'SMT'          | ''          | ''            | '20170602'
 '270UF'  | '16V'   | '20%'       | 'THLF'      | 'OSCON'    | 'CC72703MD31'(!)             = ''              | ''                 | 'CC72703MD31'                |'EC98_248_315XA'| '270UF'  | '16V'         | '20%'       | 'DISCRETE' | 'CAP OSCON DIP 270U 16V(20%,6.3*8)NPN'                 | 'DIP'          | ''          | ''            | '20170628'
 '270UF'  | '16V'   | '20%'       | 'THLF'      | 'EMPTY'    | 'CC72703MD31'(!)             = ''              | ''                 | 'CC72703MD31'                |'EC98_248_315XA'| '270UF'  | '16V'         | '20%'       | 'IO'       | 'CAP OSCON DIP 270U 16V(20%,6.3*8)NPN'                 | 'DIP'          | ''          | ''            | '20170628'
 '270UF'  | '16V'   | '20%'       | 'THLF'      | 'OSCON'    | 'SP_CC72703MD31'(!)          = ''              | ''                 | 'CC72703MD31'                |'G_EC98_248_315XA'| '270UF'  | '16V'         | '20%'       | 'DISCRETE' | 'CAP OSCON DIP 270U 16V(20%,6.3*8)NPN_FOR SEL'         | 'DIP'          | ''          | ''            | '20170628'
 '270UF'  | '16V'   | '20%'       | 'THLF'      | 'EMPTY'    | 'SP_CC72703MD31'(!)          = ''              | ''                 | 'CC72703MD31'                |'G_EC98_248_315XA'| '270UF'  | '16V'         | '20%'       | 'IO'       | 'CAP OSCON DIP 270U 16V(20%,6.3*8)NPN_FOR SEL'         | 'DIP'          | ''          | ''            | '20170628'
 '15UF'   | '25V'   | '20%'       | 'SMLF'      | 'ALUM'     | 'CC61504MZ05'(!)             = ''              | ''                 | 'CC61504MZ05'                |'EC75_248_174S'| '15UF'   | '25V'         | '20%'       | 'DISCRETE' | 'CAP ELECSMD15U 25V(20%,105C,6.3*4.4)NPN'              | 'SMT'          | ''          | ''            | '20170927'
 '15UF'   | '25V'   | '20%'       | 'SMLF'      | 'EMPTY'    | 'CC61504MZ05'(!)             = ''              | ''                 | 'CC61504MZ05'                |'EC75_248_174S'| '15UF'   | '25V'         | '20%'       | 'IO'       | 'CAP ELECSMD15U 25V(20%,105C,6.3*4.4)NPN'              | 'SMT'          | ''          | ''            | '20170927'
 '220UF'  | '2V'    | '20%'       | 'SMLF'      | 'POSCAP'   | 'CH722RM8811'(!)             = ''              | ''                 | 'CH722RM8811'                |'TAJ_SX_H40'| '220UF'  | '2V'          | '20%'       | 'DISCRETE' | 'CAP CHIP 220U 2V(20%ESR4.5,SPCAP,7343)H1'             | 'SMT'          | ''          | ''            | '20171017'
 '220UF'  | '2V'    | '20%'       | 'SMLF'      | 'EMPTY'    | 'CH722RM8811'(!)             = ''              | ''                 | 'CH722RM8811'                |'TAJ_SX_H40'| '220UF'  | '2V'          | '20%'       | 'IO'       | 'CAP CHIP 220U 2V(20%ESR4.5,SPCAP,7343)H1'             | 'SMT'          | ''          | ''            | '20171017'
 '470UF'  | '2V'    | '20%'       | 'SMLF'      | 'TANT'     | 'CH747RM8803'(!)             = ''              | ''                 | 'CH747RM8803'                |'TAJ_SX'| '470UF'  | '2V'          | '20%'       | 'DISCRETE' | 'CAP CHIP 470U 2V(20%.ESR4.5.7343.H1.8)'               | 'SMT'          | ''          | ''            | '20171024'
 '470UF'  | '2V'    | '20%'       | 'SMLF'      | 'EMPTY'    | 'CH747RM8803'(!)             = ''              | ''                 | 'CH747RM8803'                |'TAJ_SX'| '470UF'  | '2V'          | '20%'       | 'IO'       | 'CAP CHIP 470U 2V(20%.ESR4.5.7343.H1.8)'               | 'SMT'          | ''          | ''            | '20171024'
 '220UF'  | '6.3V'  | '20%'       | 'SMLF'      | 'TANT'     | 'CH7221M8600'(!)             = 'End of Design' | 'Comp-Release Qty' | 'CH7221M8600'                |'TAJ_B2XA'| '220UF'  | '6.3V'        | '20%'       | 'DISCRETE' | 'CAP CHIP 220U 6.3V(+-20%,ESR35,3528)H1.9'             | 'SMT'          | ''          | ''            | '20171129'
 '220UF'  | '6.3V'  | '20%'       | 'SMLF'      | 'EMPTY'    | 'CH7221M8600'(!)             = 'End of Design' | 'Comp-Release Qty' | 'CH7221M8600'                |'TAJ_B2XA'| '220UF'  | '6.3V'        | '20%'       | 'IO'       | 'CAP CHIP 220U 6.3V(+-20%,ESR35,3528)H1.9'             | 'SMT'          | ''          | ''            | '20171129'
 '330UF'  | '2V'    | '35%'       | 'SMLF'      | 'SPCAP'    | 'CH733RY8807'(!)             = ''              | ''                 | 'CH733RY8807'                |'TAJ_DXC'| '330U'   | '2V'          | '35%'       | 'DISCRETE' | 'CAP CHIP 330U 2V(+10-35%,SPCAP,7343)MAT'              | 'SMT'          | ''          | ''            | '20171206'
 '330UF'  | '2V'    | '35%'       | 'SMLF'      | 'EMPTY'    | 'CH733RY8807'(!)             = ''              | ''                 | 'CH733RY8807'                |'TAJ_DXC'| '330U'   | '2V'          | '35%'       | 'IO'       | 'CAP CHIP 330U 2V(+10-35%,SPCAP,7343)MAT'              | 'SMT'          | ''          | ''            | '20171206'
 '560UF'  | '2.5V'  | '20%'       | 'SMLF'      | 'OSCON'    | 'CC7560JMZ15'(!)             = ''              | ''                 | 'CC7560JMZ15'                |'EC83_248_232S'| '560UF'  | '2.5V'        | '20%'       | 'DISCRETE' | 'CAP OSCON 560U 2.5V(20%.105C.6.3*5.7)SMD'             | 'SMT'          | ''          | ''            | '20180201'
 '560UF'  | '2.5V'  | '20%'       | 'SMLF'      | 'EMPTY'    | 'CC7560JMZ15'(!)             = ''              | ''                 | 'CC7560JMZ15'                |'EC83_248_232S'| '560UF'  | '2.5V'        | '20%'       | 'IO'       | 'CAP OSCON 560U 2.5V(20%.105C.6.3*5.7)SMD'             | 'SMT'          | ''          | ''            | '20180201'
 '15UF'   | '25V'   | '20%'       | 'SMLF'      | 'OSCON'    | 'CC61504MZ07'(!)             = ''              | ''                 | 'CC61504MZ07'                |'EC83_248_166S'| '15U'    | '25V'         | '20%'       | 'DISCRETE' | 'CAP OSCON SMD 15U 25V(20%,6.3*4.4)SAY'                | 'SMT'          | ''          | ''            | '20180323'
 '15UF'   | '25V'   | '20%'       | 'SMLF'      | 'EMPTY'    | 'CC61504MZ07'(!)             = ''              | ''                 | 'CC61504MZ07'                |'EC83_248_166S'| '15U'    | '25V'         | '20%'       | 'IO'       | 'CAP OSCON SMD 15U 25V(20%,6.3*4.4)SAY'                | 'SMT'          | ''          | ''            | '20180323'
 '560UF'  | '16V'   | '20%'       | 'SMLF'      | 'OSCON'    | 'CC75603MZ00'(!)             = 'End of Design' | 'Comp-Approve'     | 'CC75603MZ00'                |'EC122_315_394S'| '560UF'  | '16V'         | '20%'       | 'DISCRETE' | 'CAP OSCON SMD 560U 16V(20%,ESR18,8*10)'               | 'SMT'          | ''          | ''            | '20170810'
 '560UF'  | '16V'   | '20%'       | 'SMLF'      | 'EMPTY'    | 'CC75603MZ00'(!)             = 'End of Design' | 'Comp-Approve'     | 'CC75603MZ00'                |'EC122_315_394S'| '560UF'  | '16V'         | '20%'       | 'IO'       | 'CAP OSCON SMD 560U 16V(20%,ESR18,8*10)'               | 'SMT'          | ''          | ''            | '20170810'
 '220UF'  | '6.3V'  | '20%'       | 'SMLF'      | 'OSCON'    | 'CC72201MZ03'(!)             = ''              | ''                 | 'CC72201MZ03'                |'EC83_248_166S'| '220U'   | '6.3V'        | '20%'       | 'DISCRETE' | 'CAP ELEC SMD 220U 6.3V(+-20%.6.3*4.2)'                | 'SMT'          | ''          | ''            | '20180515'
 '220UF'  | '6.3V'  | '20%'       | 'SMLF'      | 'EMPTY'    | 'CC72201MZ03'(!)             = ''              | ''                 | 'CC72201MZ03'                |'EC83_248_166S'| '220U'   | '6.3V'        | '20%'       | 'IO'       | 'CAP ELEC SMD 220U 6.3V(+-20%.6.3*4.2)'                | 'SMT'          | ''          | ''            | '20180515'
 '150UF'  | '6.3V'  | '20%'       | 'SMLF'      | ''         | 'CC71501MZ07'(!)             = 'End of Design' | 'Comp-Approve'     | 'CC71501MZ07'                |'EC56_197_158S'| '150UF'  | '6.3V'        | '20%'       | 'DISCRETE' | 'CAP ELEC SMD 150U 6.3V(20%,ESR20,5*3.9)'              | 'SMT'          | ''          | ''            | '20180515'
 '150UF'  | '6.3V'  | '20%'       | 'SMLF'      | 'EMPTY'    | 'CC71501MZ07'(!)             = 'End of Design' | 'Comp-Approve'     | 'CC71501MZ07'                |'EC56_197_158S'| '150UF'  | '6.3V'        | '20%'       | 'IO'       | 'CAP ELEC SMD 150U 6.3V(20%,ESR20,5*3.9)'              | 'SMT'          | ''          | ''            | '20180515'
 '470UF'  | '2.5V'  | '20%'       | 'SMLF'      | 'OSCON'    | 'CC7470JMD00'(!)             = ''              | ''                 | 'CC7470JMD00'                |'EC79_213_374'| '470UF'  | '2.5V'        | '20%'       | 'DISCRETE' | 'CAP OSCON DIP 470U 2.5V(20%,5.4*8)'                   | 'DIP'          | ''          | ''            | '20180605'
 '470UF'  | '2.5V'  | '20%'       | 'SMLF'      | 'EMPTY'    | 'CC7470JMD00'(!)             = ''              | ''                 | 'CC7470JMD00'                |'EC79_213_374'| '470UF'  | '2.5V'        | '20%'       | 'IO'       | 'CAP OSCON DIP 470U 2.5V(20%,5.4*8)'                   | 'DIP'          | ''          | ''            | '20180605'
 '470UF'  | '16V'   | '20%'       | 'THLF'      | ''         | 'CC74703MD18'(!)             = 'End of Design' | 'Comp-Approve'     | 'CC74703MD18'                |'EC138_315_453'| '470UF'  | '16V'         | '20%'       | 'DISCRETE' | 'CAP ELEC DIP 470U 16V(+-20%,105C,8*11.5)'             | 'DIP'          | ''          | ''            | '20180605'
 '470UF'  | '16V'   | '20%'       | 'THLF'      | 'EMPTY'    | 'CC74703MD18'(!)             = 'End of Design' | 'Comp-Approve'     | 'CC74703MD18'                |'EC138_315_453'| '470UF'  | '16V'         | '20%'       | 'IO'       | 'CAP ELEC DIP 470U 16V(+-20%,105C,8*11.5)'             | 'DIP'          | ''          | ''            | '20180605'
 '47UF'   | '20V'   | '20%'       | 'SMLF'      | 'ALUM'     | 'CC6470HMZ00'(!)             = 'End of Design' | 'Comp-Approve'     | 'CC6470HMZ00'                |'EC75_248_174S'| '47UF'   | '20V'         | '20%'       | 'DISCRETE' | 'CAP ELEC SMD 47U 20V(20%,105C,6.3*4.4)'               | 'SMT'          | ''          | ''            | '20180926'
 '47UF'   | '20V'   | '20%'       | 'SMLF'      | 'EMPTY'    | 'CC6470HMZ00'(!)             = 'End of Design' | 'Comp-Approve'     | 'CC6470HMZ00'                |'EC75_248_174S'| '47UF'   | '20V'         | '20%'       | 'IO'       | 'CAP ELEC SMD 47U 20V(20%,105C,6.3*4.4)'               | 'SMT'          | ''          | ''            | '20180926'
 '560U'   | '100V'  | '20%'       | 'THLF'      | 'ALUM'     | 'CC75608MD00'(!)             = ''              | 'End of Life'      | 'CC75608MD00'                |'EC296_709_985_EOL'| '560U'   | '100V'        | '20%'       | 'DISCRETE' | 'CAP ELEC DIP 560U 100V(20%,18*25)'                    | 'DIP'          | ''          | ''            | '20180928'
 '560U'   | '100V'  | '20%'       | 'THLF'      | 'EMPTY'    | 'CC75608MD00'(!)             = ''              | 'End of Life'      | 'CC75608MD00'                |'EC296_709_985_EOL'| '560U'   | '100V'        | '20%'       | 'IO'       | 'CAP ELEC DIP 560U 100V(20%,18*25)'                    | 'DIP'          | ''          | ''            | '20180928'
 '470U'   | '25V'   | '20%'       | 'SMLF'      | ''         | 'CC74704MZ26'(!)             = ''              | ''                 | 'CC74704MZ26'                |'EC181_394_402SXA'| '470U'   | '25V'         | '20%'       | 'DISCRETE' | 'CAP ELEC 470U25V(20%105C,10*10.2 ESR)'                | 'SMT'          | ''          | ''            | '20180928'
 '470U'   | '25V'   | '20%'       | 'SMLF'      | 'EMPTY'    | 'CC74704MZ26'(!)             = ''              | ''                 | 'CC74704MZ26'                |'EC181_394_402SXA'| '470U'   | '25V'         | '20%'       | 'IO'       | 'CAP ELEC 470U25V(20%105C,10*10.2 ESR)'                | 'SMT'          | ''          | ''            | '20180928'
 '10F'    | '3V'    | '20%'       | 'SMLF'      | ''         | 'CCC100KMD00'(!)             = ''              | ''                 | 'CCC100KMD00'                |'EC197_394_1182'| '10F'    | '3V'          | '20%'       | 'DISCRETE' | 'CAP ELEC DIP 10F 3V (20%,10*30)SUPER'                 | 'DIP'          | ''          | ''            | '20181005'
 '10F'    | '3V'    | '20%'       | 'SMLF'      | 'EMPTY'    | 'CCC100KMD00'(!)             = ''              | ''                 | 'CCC100KMD00'                |'EC197_394_1182'| '10F'    | '3V'          | '20%'       | 'IO'       | 'CAP ELEC DIP 10F 3V (20%,10*30)SUPER'                 | 'DIP'          | ''          | ''            | '20181005'
 '25F'    | '3V'    | '30%'       | 'THLF'      | '    '     | 'CCC250KZD00'(!)             = 'Non-Preferred' | 'End of Life'      | 'CCC250KZD00'                |'EC296_650_1119_EOL'| '25F'    | '3V'          | '30%'       | 'DISCRETE' | 'CAP ELEC DIP 25F 3V(-10/+30%,16*25)SUPER'             | 'DIP'          | ''          | ''            | '20181012'
 '25F'    | '3V'    | '30%'       | 'THLF'      | 'EMPTY'    | 'CCC250KZD00'(!)             = 'Non-Preferred' | 'End of Life'      | 'CCC250KZD00'                |'EC296_650_1119_EOL'| '25F'    | '3V'          | '30%'       | 'IO'       | 'CAP ELEC DIP 25F 3V(-10/+30%,16*25)SUPER'             | 'DIP'          | ''          | ''            | '20181012'
 '6800U'  | '16V'   | '20%'       | 'SMLF'      | ''         | 'CC86803MD00'(!)             = ''              | ''                 | 'CC86803MD00'                |'EC296_630_1241'| '6800U'  | '16V'         | '20%'       | 'DISCRETE' | 'CAP ELEC DIP 6800U 16V(20%,16*31.5)'                  | 'DIP'          | ''          | ''            | '20181015'
 '6800U'  | '16V'   | '20%'       | 'SMLF'      | 'EMPTY'    | 'CC86803MD00'(!)             = ''              | ''                 | 'CC86803MD00'                |'EC296_630_1241'| '6800U'  | '16V'         | '20%'       | 'IO'       | 'CAP ELEC DIP 6800U 16V(20%,16*31.5)'                  | 'DIP'          | ''          | ''            | '20181015'
 '3900U'  | '16V'   | '20%'       | 'SMLF'      | ''         | 'CC83903MD02'(!)             = ''              | ''                 | 'CC83903MD02'                |'EC197_493_1182'| '3900U'  | '16V'         | '20%'       | 'DISCRETE' | 'CAP ELEC DIP 3900U 16V(20%,12.5*30)'                  | 'DIP'          | ''          | ''            | '20181015'
 '3900U'  | '16V'   | '20%'       | 'SMLF'      | 'EMPTY'    | 'CC83903MD02'(!)             = ''              | ''                 | 'CC83903MD02'                |'EC197_493_1182'| '3900U'  | '16V'         | '20%'       | 'IO'       | 'CAP ELEC DIP 3900U 16V(20%,12.5*30)'                  | 'DIP'          | ''          | ''            | '20181015'
 '150UF'  | '16V'   | '20%'       | 'SMLF'      | 'OSCON'    | 'CC71503MZ00'(!)             = ''              | ''                 | 'CC71503MZ00'                |'EC83_248_232S'| '150UF'  | '16V'         | '20%'       | 'DISCRETE' | 'CAP OSCON SMD 150U 16V(20%.105C.6.3*5.9)'             | 'SMT'          | ''          | ''            | '20181018'
 '150UF'  | '16V'   | '20%'       | 'SMLF'      | 'EMPTY'    | 'CC71503MZ00'(!)             = ''              | ''                 | 'CC71503MZ00'                |'EC83_248_232S'| '150UF'  | '16V'         | '20%'       | 'IO'       | 'CAP OSCON SMD 150U 16V(20%.105C.6.3*5.9)'             | 'SMT'          | ''          | ''            | '20181018'
 '10F'    | '3V'    | '30%'       | 'THLF'      | ''         | 'CCC100KTD00'(!)             = ''              | ''                 | 'CCC100KTD00'                |'EC197_414_1241'| '10F'    | '3V'          | '30%'       | 'DISCRETE' | 'CAP ELEC DIP 10F 3V(-10/+30%,10*30)SUPER'             | 'DIP'          | ''          | ''            | '20181023'
 '10F'    | '3V'    | '30%'       | 'THLF'      | 'EMPTY'    | 'CCC100KTD00'(!)             = ''              | ''                 | 'CCC100KTD00'                |'EC197_414_1241'| '10F'    | '3V'          | '30%'       | 'IO'       | 'CAP ELEC DIP 10F 3V(-10/+30%,10*30)SUPER'             | 'DIP'          | ''          | ''            | '20181023'
 '390UF'  | '20V'   | '20%'       | 'SMLF'      | 'OSCON'    | 'CC73903MZ01'(!)             = ''              | ''                 | 'CC73903MZ01'                |'EC122_315_394S'| '390UF'  | '20V'         | '20%'       | 'DISCRETE' | 'CAP OSCON SMD 390U 20V(20%,8*10)NPN'                  | 'SMT'          | ''          | ''            | '20181026'
 '390UF'  | '20V'   | '20%'       | 'SMLF'      | 'EMPTY'    | 'CC73903MZ01'(!)             = ''              | ''                 | 'CC73903MZ01'                |'EC122_315_394S'| '390UF'  | '20V'         | '20%'       | 'IO'       | 'CAP OSCON SMD 390U 20V(20%,8*10)NPN'                  | 'SMT'          | ''          | ''            | '20181026'
 '390UF'  | '20V'   | '20%'       | 'SMLF'      | 'OSCON'    | 'CC73903MZ00'(!)             = ''              | ''                 | 'CC73903MZ00'                |'EC126_315_469SXA'| '390UF'  | '20V'         | '20%'       | 'DISCRETE' | 'CAP OSCON SMD 390U 20V(20%,8*11.9)SAY'                | 'SMT'          | ''          | ''            | '20181026'
 '390UF'  | '20V'   | '20%'       | 'SMLF'      | 'EMPTY'    | 'CC73903MZ00'(!)             = ''              | ''                 | 'CC73903MZ00'                |'EC126_315_469SXA'| '390UF'  | '20V'         | '20%'       | 'IO'       | 'CAP OSCON SMD 390U 20V(20%,8*11.9)SAY'                | 'SMT'          | ''          | ''            | '20181026'
 '560UF'  | '20V'   | '20%'       | 'SMLF'      | 'OSCON'    | 'CC75603MZ05'(!)             = ''              | ''                 | 'CC75603MZ05'                |'EC181_394_496SXA'| '560UF'  | '20V'         | '20%'       | 'DISCRETE' | 'CAP OSCON SMD 560U 20V(20%,10*12.6)SAY'               | 'SMT'          | ''          | ''            | '20181026'
 '560UF'  | '20V'   | '20%'       | 'SMLF'      | 'EMPTY'    | 'CC75603MZ05'(!)             = ''              | ''                 | 'CC75603MZ05'                |'EC181_394_496SXA'| '560UF'  | '20V'         | '20%'       | 'IO'       | 'CAP OSCON SMD 560U 20V(20%,10*12.6)SAY'               | 'SMT'          | ''          | ''            | '20181026'
 '560UF'  | '20V'   | '20%'       | 'SMLF'      | 'OSCON'    | 'CC75603MZ06'(!)             = ''              | ''                 | 'CC75603MZ06'                |'EC178_394_394SXA_H414'| '560UF'  | '20V'         | '20%'       | 'DISCRETE' | 'CAP OSCON SMD 560U 20V(20%,10*10)NPN'                 | 'SMT'          | ''          | ''            | '20181026'
 '560UF'  | '20V'   | '20%'       | 'SMLF'      | 'EMPTY'    | 'CC75603MZ06'(!)             = ''              | ''                 | 'CC75603MZ06'                |'EC178_394_394SXA_H414'| '560UF'  | '20V'         | '20%'       | 'IO'       | 'CAP OSCON SMD 560U 20V(20%,10*10)NPN'                 | 'SMT'          | ''          | ''            | '20181026'
 '2200U'  | '16V'   | '20%'       | 'THLF'      | '     '    | 'CC82203MD06'(!)             = ''              | ''                 | 'CC82203MD06'                |'EC197_394_1182'| '2200U'  | '16V'         | '20%'       | 'DISCRETE' | 'CAP ELEC DIP 2200U 16V(20%,10*30)'                    | 'DIP'          | ''          | ''            | '20181108'
 '2200U'  | '16V'   | '20%'       | 'THLF'      | 'EMPTY'    | 'CC82203MD06'(!)             = ''              | ''                 | 'CC82203MD06'                |'EC197_394_1182'| '2200U'  | '16V'         | '20%'       | 'IO'       | 'CAP ELEC DIP 2200U 16V(20%,10*30)'                    | 'DIP'          | ''          | ''            | '20181108'
 '1000U'  | '16V'   | '20%'       | 'SMLF'      | 'OSCON'    | 'CC81003MZ01'(!)             = 'End of Design' | 'Comp-Approve'     | 'CC81003MZ01'                |'EC178_394_394SXA_H414'| '1000U'  | '16V'         | '20%'       | 'DISCRETE' | 'CAP OSCON SMD 1000U 16V(20%,ESR18,10*10)'             | 'SMT'          | ''          | ''            | '20181119'
 '1000U'  | '16V'   | '20%'       | 'SMLF'      | 'EMPTY'    | 'CC81003MZ01'(!)             = 'End of Design' | 'Comp-Approve'     | 'CC81003MZ01'                |'EC178_394_394SXA_H414'| '1000U'  | '16V'         | '20%'       | 'IO'       | 'CAP OSCON SMD 1000U 16V(20%,ESR18,10*10)'             | 'SMT'          | ''          | ''            | '20181119'
 '3900U'  | '16V'   | '20%'       | 'THLF'      | ''         | 'CC83903MD05'(!)             = ''              | ''                 | 'CC83903MD05'                |'EC197_493_493_R'| '3900U'  | '16V'         | '20%'       | 'DISCRETE' | 'CAP ELEC DIP 3900U 16V(20%,12.5*30)NPN'               | 'DIP'          | ''          | ''            | '20190107'
 '3900U'  | '16V'   | '20%'       | 'THLF'      | 'EMPTY'    | 'CC83903MD05'(!)             = ''              | ''                 | 'CC83903MD05'                |'EC197_493_493_R'| '3900U'  | '16V'         | '20%'       | 'IO'       | 'CAP ELEC DIP 3900U 16V(20%,12.5*30)NPN'               | 'DIP'          | ''          | ''            | '20190107'
 '25F'    | '3V'    | '30%'       | 'THLF'      | ''         | 'CCC250KTD02'(!)             = ''              | ''                 | 'CCC250KTD02'                |'EC296_650_650_R'| '25F'    | '3V'          | '30%'       | 'DISCRETE' | 'CAP ELEC DIP 25F 3V(-10/+30%,16*25)SUPER'             | 'DIP'          | ''          | ''            | '20190107'
 '25F'    | '3V'    | '30%'       | 'THLF'      | 'EMPTY'    | 'CCC250KTD02'(!)             = ''              | ''                 | 'CCC250KTD02'                |'EC296_650_650_R'| '25F'    | '3V'          | '30%'       | 'IO'       | 'CAP ELEC DIP 25F 3V(-10/+30%,16*25)SUPER'             | 'DIP'          | ''          | ''            | '20190107'
 '560U'   | '100V'  | '20%'       | 'THLF'      | 'ALUM'     | 'CC75608MD01'(!)             = ''              | ''                 | 'CC75608MD01'                |'EC7-5_18-5_26-5'| '560U'   | '100V'        | '20%'       | 'DISCRETE' | 'CAP ELEC DIP 560U 100V(20%,18*25)'                    | 'DIP'          | ''          | ''            | '20190110'
 '560U'   | '100V'  | '20%'       | 'THLF'      | 'EMPTY'    | 'CC75608MD01'(!)             = ''              | ''                 | 'CC75608MD01'                |'EC7-5_18-5_26-5'| '560U'   | '100V'        | '20%'       | 'IO'       | 'CAP ELEC DIP 560U 100V(20%,18*25)'                    | 'DIP'          | ''          | ''            | '20190110'
 '3900U'  | '16V'   | '20%'       | 'THLF'      | ''         | 'CC83903MD06'(!)             = ''              | ''                 | 'CC83903MD06'                |'EC197_493_493_RXA'| '3900U'  | '16V'         | '20%'       | 'DISCRETE' | 'CAP ELEC DIP 3900U 16V(20%,12.5*30)MAT'               | 'DIP'          | ''          | ''            | '20190110'
 '3900U'  | '16V'   | '20%'       | 'THLF'      | 'EMPTY'    | 'CC83903MD06'(!)             = ''              | ''                 | 'CC83903MD06'                |'EC197_493_493_RXA'| '3900U'  | '16V'         | '20%'       | 'IO'       | 'CAP ELEC DIP 3900U 16V(20%,12.5*30)MAT'               | 'DIP'          | ''          | ''            | '20190110'
 '3900U'  | '16V'   | '20%'       | 'THLF'      | ''         | 'CC83903MD04'(!)             = ''              | ''                 | 'CC83903MD04'                |'EC197_493_493_R'| '3900U'  | '16V'         | '20%'       | 'DISCRETE' | 'CAP ELEC DIP 3900U 16V(20%,12.5*30)'                  | 'DIP'          | ''          | ''            | '20190110'
 '3900U'  | '16V'   | '20%'       | 'THLF'      | 'EMPTY'    | 'CC83903MD04'(!)             = ''              | ''                 | 'CC83903MD04'                |'EC197_493_493_R'| '3900U'  | '16V'         | '20%'       | 'IO'       | 'CAP ELEC DIP 3900U 16V(20%,12.5*30)'                  | 'DIP'          | ''          | ''            | '20190110'
 '47U'    | '20V'   | '20%'       | 'SMLF'      | 'ALUM'     | 'CC6470HMZ02'(!)             = 'End of Design' | 'Comp-Approve'     | 'CC6470HMZ02'                |'EC75_248_174S'| '47UF'   | '20V'         | '20%'       | 'DISCRETE' | 'CAP ELEC SMD 47U 20V(20%,6.3*4.4)NPN'                 | 'SMT'          | ''          | ''            | '20190116'
 '47U'    | '20V'   | '20%'       | 'SMLF'      | 'EMPTY'    | 'CC6470HMZ02'(!)             = 'End of Design' | 'Comp-Approve'     | 'CC6470HMZ02'                |'EC75_248_174S'| '47UF'   | '20V'         | '20%'       | 'IO'       | 'CAP ELEC SMD 47U 20V(20%,6.3*4.4)NPN'                 | 'SMT'          | ''          | ''            | '20190116'
 '330UF'  | '100V'  | '20%'       | 'SMLF'      | 'ALUM'     | 'CC73308MZ00'(!)             = ''              | ''                 | 'CC73308MZ00'                |'EC264_709_650S_H670'| '330UF'  | '100V'        | '20%'       | 'DISCRETE' | 'CAP ELEC SMD 330U 100V(20%,18*16.5)AEC'               | 'SMT'          | ''          | ''            | '20190212'
 '330UF'  | '100V'  | '20%'       | 'SMLF'      | 'EMPTY'    | 'CC73308MZ00'(!)             = ''              | ''                 | 'CC73308MZ00'                |'EC264_709_650S_H670'| '330UF'  | '100V'        | '20%'       | 'IO'       | 'CAP ELEC SMD 330U 100V(20%,18*16.5)AEC'               | 'SMT'          | ''          | ''            | '20190212'
 '47U'    | '80V'   | '20%'       | 'SMLF'      | 'ALUM'     | 'CC6470EMZ01'(!)             = ''              | ''                 | 'CC6470EMZ01'                |'EC181_394_496SXA'| '47U'    | '80V'         | '20%'       | 'DISCRETE' | 'CAP OSCON SMD 47U 80V(20%,ESR28,10*12.6)'             | 'SMT'          | ''          | ''            | '20190215'
 '47U'    | '80V'   | '20%'       | 'SMLF'      | 'EMPTY'    | 'CC6470EMZ01'(!)             = ''              | ''                 | 'CC6470EMZ01'                |'EC181_394_496SXA'| '47U'    | '80V'         | '20%'       | 'IO'       | 'CAP OSCON SMD 47U 80V(20%,ESR28,10*12.6)'             | 'SMT'          | ''          | ''            | '20190215'
 '560UF'  | '16V'   | '20%'       | 'THLF'      | 'OSCON'    | 'CC75603MD01'(!)             = ''              | ''                 | 'CC75603MD01'                |'EC98_248_433XA'| '560UF'  | '16V'         | '20%'       | 'DISCRETE' | 'CAP OSCON DIP 560U 16V(20%,ESR20,6.3*11)'             | 'DIP'          | ''          | ''            | '20190521'
 '560UF'  | '16V'   | '20%'       | 'THLF'      | 'EMPTY'    | 'CC75603MD01'(!)             = ''              | ''                 | 'CC75603MD01'                |'EC98_248_433XA'| '560UF'  | '16V'         | '20%'       | 'IO'       | 'CAP OSCON DIP 560U 16V(20%,ESR20,6.3*11)'             | 'DIP'          | ''          | ''            | '20190521'
 '220UF'  | '25V'   | '20%'       | 'THLF'      | 'OSCON'    | 'CC72204MD02'(!)             = ''              | ''                 | 'CC72204MD02'                |'EC3-5_8-5_13XA'| '220UF'  | '25V'         | '20%'       | 'DISCRETE' | 'CAP OSCON DIP 220U 25V(20%,8*11.5)NPN'                | 'DIP'          | ''          | ''            | '20190625'
 '220UF'  | '25V'   | '20%'       | 'THLF'      | 'EMPTY'    | 'CC72204MD02'(!)             = ''              | ''                 | 'CC72204MD02'                |'EC3-5_8-5_13XA'| '220UF'  | '25V'         | '20%'       | 'IO'       | 'CAP OSCON DIP 220U 25V(20%,8*11.5)NPN'                | 'DIP'          | ''          | ''            | '20190625'
 '220UF'  | '25V'   | '20%'       | 'THLF'      | 'OSCON'    | 'SP_CC72204MD02'(!)          = ''              | ''                 | 'CC72204MD02'                |'G_EC3-5_8-5_13XA'| '220UF'  | '25V'         | '20%'       | 'DISCRETE' | 'CAP OSCON DIP 220U 25V(20%,8*11.5)NPN_FOR SEL'        | 'DIP'          | ''          | ''            | '20190625'
 '220UF'  | '25V'   | '20%'       | 'THLF'      | 'EMPTY'    | 'SP_CC72204MD02'(!)          = ''              | ''                 | 'CC72204MD02'                |'G_EC3-5_8-5_13XA'| '220UF'  | '25V'         | '20%'       | 'IO'       | 'CAP OSCON DIP 220U 25V(20%,8*11.5)NPN_FOR SEL'        | 'DIP'          | ''          | ''            | '20190625'
 '100UF'  | '16V'   | '+10/-35%'  | 'SMLF'      | 'ALUM'     | 'CC71003TZ01'(!)             = ''              | ''                 | 'CC71003TZ01'                |'EC56_197_233S'| '100UF'  | '16V'         | '+10/-35%'  | 'DISCRETE' | 'CAPOSCON SMD 100U 16V(+10/-35%,5*5.9)SAY'             | 'SMT'          | ''          | ''            | '20190625'
 '100UF'  | '16V'   | '+10/-35%'  | 'SMLF'      | 'EMPTY'    | 'CC71003TZ01'(!)             = ''              | ''                 | 'CC71003TZ01'                |'EC56_197_233S'| '100UF'  | '16V'         | '+10/-35%'  | 'IO'       | 'CAPOSCON SMD 100U 16V(+10/-35%,5*5.9)SAY'             | 'SMT'          | ''          | ''            | '20190625'
 '330UF'  | '16V'   | '20%'       | 'SMLF'      | 'OSCON'    | 'CC73303MZ06'(!)             = ''              | ''                 | 'CC73303MZ06'                |'EC126_315_272SXA'| '330UF'  | '16V'         | '20%'       | 'DISCRETE' | 'CAP OSCON SMD 330U 16V(20%,8*6.9)'                    | 'SMT'          | ''          | ''            | '20190626'
 '330UF'  | '16V'   | '20%'       | 'SMLF'      | 'EMPTY'    | 'CC73303MZ06'(!)             = ''              | ''                 | 'CC73303MZ06'                |'EC126_315_272SXA'| '330UF'  | '16V'         | '20%'       | 'IO'       | 'CAP OSCON SMD 330U 16V(20%,8*6.9)'                    | 'SMT'          | ''          | ''            | '20190626'
 '27UF'   | '80V'   | '20%'       | 'SMLF'      | 'OSCON'    | 'CC6270EMZ00'(!)             = ''              | ''                 | 'CC6270EMZ00'                |'EC181_394_311SXA'| '27UF'   | '80V'         | '20%'       | 'DISCRETE' | 'CAP OSCON SMD 27U 80V(20%,10*7.9)'                    | 'SMT'          | ''          | ''            | '20190626'
 '27UF'   | '80V'   | '20%'       | 'SMLF'      | 'EMPTY'    | 'CC6270EMZ00'(!)             = ''              | ''                 | 'CC6270EMZ00'                |'EC181_394_311SXA'| '27UF'   | '80V'         | '20%'       | 'IO'       | 'CAP OSCON SMD 27U 80V(20%,10*7.9)'                    | 'SMT'          | ''          | ''            | '20190626'
 '220UF'  | '25V'   | '20%'       | 'THLF'      | 'OSCON'    | 'CC72204MD01'(!)             = ''              | ''                 | 'CC72204MD01'                |'EC138_315_453XB'| '220UF'  | '25V'         | '20%'       | 'DISCRETE' | 'CAP OSCON DIP 220U 25V(20%,8*11.5)APQ'                | 'DIP'          | ''          | ''            | '20190627'
 '220UF'  | '25V'   | '20%'       | 'THLF'      | 'EMPTY'    | 'CC72204MD01'(!)             = ''              | ''                 | 'CC72204MD01'                |'EC138_315_453XB'| '220UF'  | '25V'         | '20%'       | 'IO'       | 'CAP OSCON DIP 220U 25V(20%,8*11.5)APQ'                | 'DIP'          | ''          | ''            | '20190627'
 '270UF'  | '16V'   | '20%'       | 'SMLF'      | 'OSCON'    | 'CC72703MZ06'(!)             = 'End of Design' | 'Comp-Approve'     | 'CC72703MZ06'                |'EC75_248_382S'| '270UF'  | '16V'         | '20%'       | 'DISCRETE' | 'CAP OSCON SMD 270U 16V(20%,6.3*9.7)NPN'               | 'SMT'          | ''          | ''            | '20190627'
 '270UF'  | '16V'   | '20%'       | 'SMLF'      | 'EMPTY'    | 'CC72703MZ06'(!)             = 'End of Design' | 'Comp-Approve'     | 'CC72703MZ06'                |'EC75_248_382S'| '270UF'  | '16V'         | '20%'       | 'IO'       | 'CAP OSCON SMD 270U 16V(20%,6.3*9.7)NPN'               | 'SMT'          | ''          | ''            | '20190627'
 '270UF'  | '16V'   | '20%'       | 'SMLF'      | 'OSCON'    | 'CC72703MZ07'(!)             = ''              | ''                 | 'CC72703MZ07'                |'EC83_248_390S'| '270UF'  | '16V'         | '20%'       | 'DISCRETE' | 'CAP OSCON SMD 270U 16V(20%,6.3*9.9)SAY'               | 'SMT'          | ''          | ''            | '20190627'
 '270UF'  | '16V'   | '20%'       | 'SMLF'      | 'EMPTY'    | 'CC72703MZ07'(!)             = ''              | ''                 | 'CC72703MZ07'                |'EC83_248_390S'| '270UF'  | '16V'         | '20%'       | 'IO'       | 'CAP OSCON SMD 270U 16V(20%,6.3*9.9)SAY'               | 'SMT'          | ''          | ''            | '20190627'
 '100UF'  | '16V'   | '20%'       | 'SMLF'      | 'OSCON'    | 'CC71003MZ30'(!)             = ''              | ''                 | 'CC71003MZ30'                |'EC56_197_229SXA'| '100UF'  | '16V'         | '20%'       | 'DISCRETE' | 'CAP OSCON SMD 100U 16V(20%,5*5.8)NPN'                 | 'SMT'          | ''          | ''            | '20190627'
 '100UF'  | '16V'   | '20%'       | 'SMLF'      | 'EMPTY'    | 'CC71003MZ30'(!)             = ''              | ''                 | 'CC71003MZ30'                |'EC56_197_229SXA'| '100UF'  | '16V'         | '20%'       | 'IO'       | 'CAP OSCON SMD 100U 16V(20%,5*5.8)NPN'                 | 'SMT'          | ''          | ''            | '20190627'
 '100UF'  | '16V'   | '+10/-35%'  | 'SMLF'      | 'OSCON'    | 'CC71003TZ00'(!)             = ''              | ''                 | 'CC71003TZ00'                |'EC56_197_233S'| '100UF'  | '16V'         | '+10/-35%'  | 'DISCRETE' | 'CAPOSCONSMD 100U 16V(+10/-35%,105C,5*5.9'             | 'SMT'          | ''          | ''            | '20190627'
 '100UF'  | '16V'   | '+10/-35%'  | 'SMLF'      | 'EMPTY'    | 'CC71003TZ00'(!)             = ''              | ''                 | 'CC71003TZ00'                |'EC56_197_233S'| '100UF'  | '16V'         | '+10/-35%'  | 'IO'       | 'CAPOSCONSMD 100U 16V(+10/-35%,105C,5*5.9'             | 'SMT'          | ''          | ''            | '20190627'
 '560UF'  | '16V'   | '20%'       | 'SMLF'      | 'OSCON'    | 'CC75603MZ01'(!)             = ''              | ''                 | 'CC75603MZ01'                |'EC126_315_461S'| '560UF'  | '16V'         | '20%'       | 'DISCRETE' | 'CAP OSCON SMD 560U 16V(20%,105C,8*11.7)'              | 'SMT'          | ''          | ''            | '20190628'
 '560UF'  | '16V'   | '20%'       | 'SMLF'      | 'EMPTY'    | 'CC75603MZ01'(!)             = ''              | ''                 | 'CC75603MZ01'                |'EC126_315_461S'| '560UF'  | '16V'         | '20%'       | 'IO'       | 'CAP OSCON SMD 560U 16V(20%,105C,8*11.7)'              | 'SMT'          | ''          | ''            | '20190628'
 '560UF'  | '6.3V'  | '20%'       | 'THLF'      | 'OSCON'    | 'CC75601MD16'(!)             = ''              | ''                 | 'CC75601MD16'                |'EC2-5_6-8_9-5'| '560UF'  | '6.3V'        | '20%'       | 'DISCRETE' | 'CAP OSCON DIP 560U 6.3V(+-20%,6.3*8)NPN'              | 'DIP'          | ''          | ''            | '20190701'
 '560UF'  | '6.3V'  | '20%'       | 'THLF'      | 'EMPTY'    | 'CC75601MD16'(!)             = ''              | ''                 | 'CC75601MD16'                |'EC2-5_6-8_9-5'| '560UF'  | '6.3V'        | '20%'       | 'IO'       | 'CAP OSCON DIP 560U 6.3V(+-20%,6.3*8)NPN'              | 'DIP'          | ''          | ''            | '20190701'
 '560UF'  | '6.3V'  | '20%'       | 'THLF'      | 'OSCON'    | 'CC75601MD03'(!)             = ''              | ''                 | 'CC75601MD03'                |'EC98_248_315XB'| '560UF'  | '6.3V'        | '20%'       | 'DISCRETE' | 'CAP OSCON DIP 560U 6.3V(+-20%,6.3*8)'                 | 'DIP'          | ''          | ''            | '20190701'
 '560UF'  | '6.3V'  | '20%'       | 'THLF'      | 'EMPTY'    | 'CC75601MD03'(!)             = ''              | ''                 | 'CC75601MD03'                |'EC98_248_315XB'| '560UF'  | '6.3V'        | '20%'       | 'IO'       | 'CAP OSCON DIP 560U 6.3V(+-20%,6.3*8)'                 | 'DIP'          | ''          | ''            | '20190701'
 '270UF'  | '16V'   | '20%'       | 'THLF'      | 'OSCON'    | 'CC72703MD38'(!)             = ''              | ''                 | 'CC72703MD38'                |'EC2-5_6-8_9-2'| '270UF'  | '16V'         | '20%'       | 'DISCRETE' | 'CAPOSCON DIP 270U16V(20%,ESR10,6.3*8)NPN'             | 'DIP'          | ''          | ''            | '20190701'
 '270UF'  | '16V'   | '20%'       | 'THLF'      | 'EMPTY'    | 'CC72703MD38'(!)             = ''              | ''                 | 'CC72703MD38'                |'EC2-5_6-8_9-2'| '270UF'  | '16V'         | '20%'       | 'IO'       | 'CAPOSCON DIP 270U16V(20%,ESR10,6.3*8)NPN'             | 'DIP'          | ''          | ''            | '20190701'
 '560UF'  | '2.5V'  | '20%'       | 'THLF'      | 'OSCON'    | 'CC7560JMD16'(!)             = 'End of Design' | 'Comp-Approve'     | 'CC7560JMD16'                |'EC2_5-5_9XB'| '560UF'  | '2.5V'        | '20%'       | 'DISCRETE' | 'CAP OSCON DIP 560U 2.5V(20%,5*8)SAY'                  | 'DIP'          | ''          | ''            | '20190701'
 '560UF'  | '2.5V'  | '20%'       | 'THLF'      | 'EMPTY'    | 'CC7560JMD16'(!)             = 'End of Design' | 'Comp-Approve'     | 'CC7560JMD16'                |'EC2_5-5_9XB'| '560UF'  | '2.5V'        | '20%'       | 'IO'       | 'CAP OSCON DIP 560U 2.5V(20%,5*8)SAY'                  | 'DIP'          | ''          | ''            | '20190701'
 '560UF'  | '2.5V'  | '20%'       | 'THLF'      | 'OSCON'    | 'SP_CC7560JMD16'(!)          = 'End of Design' | 'Comp-Approve'     | 'CC7560JMD16'                |'G_EC2_5-5_9XB'| '560UF'  | '2.5V'        | '20%'       | 'DISCRETE' | 'CAP OSCON DIP 560U 2.5V(20%,5*8)SAY_FOR SEL'          | 'DIP'          | ''          | ''            | '20190701'
 '560UF'  | '2.5V'  | '20%'       | 'THLF'      | 'EMPTY'    | 'SP_CC7560JMD16'(!)          = 'End of Design' | 'Comp-Approve'     | 'CC7560JMD16'                |'G_EC2_5-5_9XB'| '560UF'  | '2.5V'        | '20%'       | 'IO'       | 'CAP OSCON DIP 560U 2.5V(20%,5*8)SAY_FOR SEL'          | 'DIP'          | ''          | ''            | '20190701'
 '330UF'  | '6.3V'  | '20%'       | 'SMLF'      | 'POSCAP'   | 'CH7331MI806'(!)             = ''              | ''                 | 'CH7331MI806'                |'TAJ_D2EXA'| '330UF'  | '6.3V'        | '20%'       | 'DISCRETE' | 'CAP CHIP 330U 6.3V(20%,POSCAP,7343)SAY'               | 'SMT'          | ''          | ''            | '20190703'
 '330UF'  | '6.3V'  | '20%'       | 'SMLF'      | 'EMPTY'    | 'CH7331MI806'(!)             = ''              | ''                 | 'CH7331MI806'                |'TAJ_D2EXA'| '330UF'  | '6.3V'        | '20%'       | 'IO'       | 'CAP CHIP 330U 6.3V(20%,POSCAP,7343)SAY'               | 'SMT'          | ''          | ''            | '20190703'
 '330UF'  | '6.3V'  | '20%'       | 'SMLF'      | 'POSCAP'   | 'CH7331MI805'(!)             = 'End of Design' | 'Comp-Approve'     | 'CH7331MI805'                |'TAJ_7343-20'| '330UF'  | '6.3V'        | '20%'       | 'DISCRETE' | 'CAP CHIP 330U 6.3V(20%,POSCAP,7343)KEM'               | 'SMT'          | ''          | ''            | '20190710'
 '330UF'  | '6.3V'  | '20%'       | 'SMLF'      | 'EMPTY'    | 'CH7331MI805'(!)             = 'End of Design' | 'Comp-Approve'     | 'CH7331MI805'                |'TAJ_7343-20'| '330UF'  | '6.3V'        | '20%'       | 'IO'       | 'CAP CHIP 330U 6.3V(20%,POSCAP,7343)KEM'               | 'SMT'          | ''          | ''            | '20190710'
 '56UF'   | '100V'  | '20%'       | 'THLF'      | 'ALUM'     | 'CC65608MD03'(!)             = ''              | ''                 | 'CC65608MD03'                |'EC197_394_492XA'| '56UF'   | '100V'        | '20%'       | 'DISCRETE' | 'CAP ELEC DIP 56U 100V(20%,105C,10*12.5)'              | 'DIP'          | ''          | ''            | '20190711'
 '56UF'   | '100V'  | '20%'       | 'THLF'      | 'EMPTY'    | 'CC65608MD03'(!)             = ''              | ''                 | 'CC65608MD03'                |'EC197_394_492XA'| '56UF'   | '100V'        | '20%'       | 'IO'       | 'CAP ELEC DIP 56U 100V(20%,105C,10*12.5)'              | 'DIP'          | ''          | ''            | '20190711'
 '56UF'   | '100V'  | '20%'       | 'THLF'      | 'ALUM'     | 'SP_CC65608MD03'(!)          = ''              | ''                 | 'CC65608MD03'                |'G_EC197_394_492XA'| '56UF'   | '100V'        | '20%'       | 'DISCRETE' | 'CAP ELEC DIP 56U 100V(20%,105C,10*12.5)_FOR SEL'      | 'DIP'          | ''          | ''            | '20190711'
 '56UF'   | '100V'  | '20%'       | 'THLF'      | 'EMPTY'    | 'SP_CC65608MD03'(!)          = ''              | ''                 | 'CC65608MD03'                |'G_EC197_394_492XA'| '56UF'   | '100V'        | '20%'       | 'IO'       | 'CAP ELEC DIP 56U 100V(20%,105C,10*12.5)_FOR SEL'      | 'DIP'          | ''          | ''            | '20190711'
 '330UF'  | '2V'    | '+10/-35%'  | 'SMLF'      | 'SPCAP'    | 'CH733RY8809'(!)             = 'End of Design' | 'End of Life'      | 'CH733RY8809'                |'TAJ_SX_EOL'| '330UF'  | '2V'          | '+10/-35%'  | 'DISCRETE' | 'CAP CHIP 330U 2V(+10/-35%,SPCAP,7343)MUR'             | 'SMT'          | ''          | ''            | '20190723'
 '330UF'  | '2V'    | '+10/-35%'  | 'SMLF'      | 'EMPTY'    | 'CH733RY8809'(!)             = 'End of Design' | 'End of Life'      | 'CH733RY8809'                |'TAJ_SX_EOL'| '330UF'  | '2V'          | '+10/-35%'  | 'IO'       | 'CAP CHIP 330U 2V(+10/-35%,SPCAP,7343)MUR'             | 'SMT'          | ''          | ''            | '20190723'
 '56UF'   | '100V'  | '20%'       | 'THLF'      | 'ALUM'     | 'CC65608MD04'(!)             = ''              | ''                 | 'CC65608MD04'                |'G_EC197_394_492XA'| '56UF'   | '100V'        | '20%'       | 'DISCRETE' | 'CAP ELEC 56UF 100V(20%,10*12.5)SEL ASS'               | 'DIP'          | ''          | ''            | '20190724'
 '56UF'   | '100V'  | '20%'       | 'THLF'      | 'EMPTY'    | 'CC65608MD04'(!)             = ''              | ''                 | 'CC65608MD04'                |'G_EC197_394_492XA'| '56UF'   | '100V'        | '20%'       | 'IO'       | 'CAP ELEC 56UF 100V(20%,10*12.5)SEL ASS'               | 'DIP'          | ''          | ''            | '20190724'
 '270UF'  | '16V'   | '20%'       | 'THLF'      | 'OSCON'    | 'CC72703MD39'(!)             = ''              | ''                 | 'CC72703MD39'                |'EC98_248_315XA'| '270UF'  | '16V'         | '20%'       | 'DISCRETE' | 'CAP OSCONDIP 270U16V(20%,ESR10,6.3*8)TOW'             | 'DIP'          | ''          | ''            | '20190806'
 '270UF'  | '16V'   | '20%'       | 'THLF'      | 'EMPTY'    | 'CC72703MD39'(!)             = ''              | ''                 | 'CC72703MD39'                |'EC98_248_315XA'| '270UF'  | '16V'         | '20%'       | 'IO'       | 'CAP OSCONDIP 270U16V(20%,ESR10,6.3*8)TOW'             | 'DIP'          | ''          | ''            | '20190806'
 '470UF'  | '2.5V'  | '20%'       | 'SMLF'      | 'SPCAP'    | 'CH747LM8819'(!)             = 'End of Design' | 'Comp-Approve'     | 'CH747LM8819'                |'TAJ_SX'| '470UF'  | '2.5V'        | '20%'       | 'DISCRETE' | 'CAPCHIP 470U 2.5V(20%,ESR4.5,7343,SPCAP)'             | 'SMT'          | ''          | ''            | '20190816'
 '470UF'  | '2.5V'  | '20%'       | 'SMLF'      | 'EMPTY'    | 'CH747LM8819'(!)             = 'End of Design' | 'Comp-Approve'     | 'CH747LM8819'                |'TAJ_SX'| '470UF'  | '2.5V'        | '20%'       | 'IO'       | 'CAPCHIP 470U 2.5V(20%,ESR4.5,7343,SPCAP)'             | 'SMT'          | ''          | ''            | '20190816'
 '56UF'   | '100V'  | '20%'       | 'THLF'      | 'ALUM'     | 'CC65608MD05'(!)             = ''              | ''                 | 'CC65608MD05'                |'EC5_10-5_14'| '56UF'   | '100V'        | '20%'       | 'DISCRETE' | 'CAP ELEC DIP 56U 100V(20%,10*12.5)NPN'                | 'DIP'          | ''          | ''            | '20190820'
 '56UF'   | '100V'  | '20%'       | 'THLF'      | 'EMPTY'    | 'CC65608MD05'(!)             = ''              | ''                 | 'CC65608MD05'                |'EC5_10-5_14'| '56UF'   | '100V'        | '20%'       | 'IO'       | 'CAP ELEC DIP 56U 100V(20%,10*12.5)NPN'                | 'DIP'          | ''          | ''            | '20190820'
 '56UF'   | '100V'  | '20%'       | 'THLF'      | 'ALUM'     | 'SP_CC65608MD05'(!)          = ''              | ''                 | 'CC65608MD05'                |'G_EC5_10-5_14'| '56UF'   | '100V'        | '20%'       | 'DISCRETE' | 'CAP ELEC DIP 56U 100V(20%,10*12.5)NPN)_FOR SEL'       | 'DIP'          | ''          | ''            | '20190820'
 '56UF'   | '100V'  | '20%'       | 'THLF'      | 'EMPTY'    | 'SP_CC65608MD05'(!)          = ''              | ''                 | 'CC65608MD05'                |'G_EC5_10-5_14'| '56UF'   | '100V'        | '20%'       | 'IO'       | 'CAP ELEC DIP 56U 100V(20%,10*12.5)NPN)_FOR SEL'       | 'DIP'          | ''          | ''            | '20190820'
 '1000UF' | '16V'   | '20%'       | 'SMLF'      | 'OSCON'    | 'CC81003MZ03'(!)             = ''              | ''                 | 'CC81003MZ03'                |'EC181_394_496SXA'| '1000UF' | '16V'         | '20%'       | 'DISCRETE' | 'CAP OSCON SMD 1000U 16V(20%,10*12.6)SAY'              | 'SMT'          | ''          | ''            | '20190906'
 '1000UF' | '16V'   | '20%'       | 'SMLF'      | 'EMPTY'    | 'CC81003MZ03'(!)             = ''              | ''                 | 'CC81003MZ03'                |'EC181_394_496SXA'| '1000UF' | '16V'         | '20%'       | 'IO'       | 'CAP OSCON SMD 1000U 16V(20%,10*12.6)SAY'              | 'SMT'          | ''          | ''            | '20190906'
 '2200UF' | '16V'   | '20%'       | 'THLF'      | 'OSCON'    | 'CC82202MD01'(!)             = ''              | ''                 | 'CC82202MD01'                |'EC5_10-5_21-5XA'| '2200UF' | '16V'         | '20%'       | 'DISCRETE' | 'CAP OSCON DIP 2200U 16V(20%,105C,10*20)'              | 'DIP'          | ''          | ''            | '20161021'
 '2200UF' | '16V'   | '20%'       | 'THLF'      | 'EMPTY'    | 'CC82202MD01'(!)             = ''              | ''                 | 'CC82202MD01'                |'EC5_10-5_21-5XA'| '2200UF' | '16V'         | '20%'       | 'IO'       | 'CAP OSCON DIP 2200U 16V(20%,105C,10*20)'              | 'DIP'          | ''          | ''            | '20161021'
 '2200UF' | '16V'   | '20%'       | 'THLF'      | 'OSCON'    | 'SP_CC82202MD01'(!)          = ''              | ''                 | 'CC82202MD01'                |'G_EC5_10-5_21-5XA'| '2200UF' | '16V'         | '20%'       | 'DISCRETE' | 'CAP OSCON DIP 2200U 16V(20%,105C,10*20)_FOR SEL'      | 'DIP'          | ''          | ''            | '20190912'
 '2200UF' | '16V'   | '20%'       | 'THLF'      | 'EMPTY'    | 'SP_CC82202MD01'(!)          = ''              | ''                 | 'CC82202MD01'                |'G_EC5_10-5_21-5XA'| '2200UF' | '16V'         | '20%'       | 'IO'       | 'CAP OSCON DIP 2200U 16V(20%,105C,10*20)_FOR SEL'      | 'DIP'          | ''          | ''            | '20190912'
 '330UF'  | '6.3V'  | '20%'       | 'SMLF'      | 'OSCON'    | 'CC73301MZ20'(!)             = ''              | ''                 | 'CC73301MZ20'                |'EC83_248_233S'| '330UF'  | '6.3V'        | '20%'       | 'DISCRETE' | 'CAP OSCON 330U 6.3V(20%,105C,6.3*5.9)SAY'             | 'SMT'          | ''          | ''            | '20190925'
 '330UF'  | '6.3V'  | '20%'       | 'SMLF'      | 'EMPTY'    | 'CC73301MZ20'(!)             = ''              | ''                 | 'CC73301MZ20'                |'EC83_248_233S'| '330UF'  | '6.3V'        | '20%'       | 'IO'       | 'CAP OSCON 330U 6.3V(20%,105C,6.3*5.9)SAY'             | 'SMT'          | ''          | ''            | '20190925'
 '47UF'   | '80V'   | '20%'       | 'SMLF'      | 'OSCON'    | 'CC6470EMZ02'(!)             = ''              | ''                 | 'CC6470EMZ02'                |'EC181_394_496SXA'| '47UF'   | '80V'         | '20%'       | 'DISCRETE' | 'CAP OSCON SMD 47U 80V(20%,10*12.6)SAY'                | 'SMT'          | ''          | ''            | '20191002'
 '47UF'   | '80V'   | '20%'       | 'SMLF'      | 'EMPTY'    | 'CC6470EMZ02'(!)             = ''              | ''                 | 'CC6470EMZ02'                |'EC181_394_496SXA'| '47UF'   | '80V'         | '20%'       | 'IO'       | 'CAP OSCON SMD 47U 80V(20%,10*12.6)SAY'                | 'SMT'          | ''          | ''            | '20191002'
 '560UF'  | '16V'   | '20%'       | 'SMLF'      | 'OSCON'    | 'CC75603MZ07'(!)             = 'End of Design' | 'Comp-Approve'     | 'CC75603MZ07'                |'EC122_315_394S'| '560UF'  | '16V'         | '20%'       | 'DISCRETE' | 'CAPOSCON SMD 560U 16V(20%,ESR18,8*10)NPN'             | 'SMT'          | ''          | ''            | '20191030'
 '560UF'  | '16V'   | '20%'       | 'SMLF'      | 'EMPTY'    | 'CC75603MZ07'(!)             = 'End of Design' | 'Comp-Approve'     | 'CC75603MZ07'                |'EC122_315_394S'| '560UF'  | '16V'         | '20%'       | 'IO'       | 'CAPOSCON SMD 560U 16V(20%,ESR18,8*10)NPN'             | 'SMT'          | ''          | ''            | '20191030'
 '330UF'  | '4V'    | '20%'       | 'SMLF'      | 'SPCAP'    | 'CH733KM8805'(!)             = ''              | ''                 | 'CH733KM8805'                |'TAJ_D9'| '330UF'  | '4V'          | '20%'       | 'DISCRETE' | 'CAP CHIP 330UF 4V(20%,SPCAP,ESR8,7343)'               | 'SMT'          | ''          | ''            | '20191213'
 '330UF'  | '4V'    | '20%'       | 'SMLF'      | 'EMPTY'    | 'CH733KM8805'(!)             = ''              | ''                 | 'CH733KM8805'                |'TAJ_D9'| '330UF'  | '4V'          | '20%'       | 'IO'       | 'CAP CHIP 330UF 4V(20%,SPCAP,ESR8,7343)'               | 'SMT'          | ''          | ''            | '20191213'
 '100UF'  | '6.3V'  | '20%'       | 'SMLF'      | 'TANT'     | 'CH7101MI604'(!)             = ''              | ''                 | 'CH7101MI604'                |'TAJ_B_T520B227M2R5ATE015'| '100UF'  | '6.3V'        | '20%'       | 'DISCRETE' | 'CAPCHIP100U 6.3V(20%POSCAP(TAN),3528)KEM'             | 'SMT'          | ''          | ''            | '20191220'
 '100UF'  | '6.3V'  | '20%'       | 'SMLF'      | 'EMPTY'    | 'CH7101MI604'(!)             = ''              | ''                 | 'CH7101MI604'                |'TAJ_B_T520B227M2R5ATE015'| '100UF'  | '6.3V'        | '20%'       | 'IO'       | 'CAPCHIP100U 6.3V(20%POSCAP(TAN),3528)KEM'             | 'SMT'          | ''          | ''            | '20191220'
 '270UF'  | '2V'    | '20%'       | 'SMLF'      | 'POSCAP'   | 'CH727RMI600'(!)             = ''              | ''                 | 'CH727RMI600'                |'TAJ_B2S'| '270UF'  | '2V'          | '20%'       | 'DISCRETE' | 'CAPCHIP 270U 2V(20%,ESR6,POSCAP,3528)SAY'             | 'SMT'          | ''          | ''            | '20200102'
 '270UF'  | '2V'    | '20%'       | 'SMLF'      | 'EMPTY'    | 'CH727RMI600'(!)             = ''              | ''                 | 'CH727RMI600'                |'TAJ_B2S'| '270UF'  | '2V'          | '20%'       | 'IO'       | 'CAPCHIP 270U 2V(20%,ESR6,POSCAP,3528)SAY'             | 'SMT'          | ''          | ''            | '20200102'
 '2200UF' | '16V'   | '20%'       | 'THLF'      | 'OSCON'    | 'CC82203MD07'(!)             = ''              | ''                 | 'CC82203MD07'                |'EC5_10-5_21-5XA'| '2200UF' | '16V'         | '20%'       | 'DISCRETE' | 'CAP OSCON DIP 2200U 16V(20%,10*20)NPN'                | 'DIP'          | ''          | ''            | '20200120'
 '2200UF' | '16V'   | '20%'       | 'THLF'      | 'EMPTY'    | 'CC82203MD07'(!)             = ''              | ''                 | 'CC82203MD07'                |'EC5_10-5_21-5XA'| '2200UF' | '16V'         | '20%'       | 'IO'       | 'CAP OSCON DIP 2200U 16V(20%,10*20)NPN'                | 'DIP'          | ''          | ''            | '20200120'
 '270UF'  | '16V'   | '20%'       | 'THLF'      | 'OSCON'    | 'CC72703MD40'(!)             = ''              | ''                 | 'CC72703MD40'                |'EC138_315_315XA'| '270UF'  | '16V'         | '20%'       | 'DISCRETE' | 'CAP OSCON DIP 270U 16V(20%,ESR10,8*8)APQ'             | 'DIP'          | ''          | ''            | '20200121'
 '270UF'  | '16V'   | '20%'       | 'THLF'      | 'EMPTY'    | 'CC72703MD40'(!)             = ''              | ''                 | 'CC72703MD40'                |'EC138_315_315XA'| '270UF'  | '16V'         | '20%'       | 'IO'       | 'CAP OSCON DIP 270U 16V(20%,ESR10,8*8)APQ'             | 'DIP'          | ''          | ''            | '20200121'
 '330UF'  | '35V'   | '20%'       | 'SMLF'      | 'ALUM'     | 'CC73305MZ24'(!)             = ''              | ''                 | 'CC73305MZ24'                |'EC178_394_394SXB'| '330UF'  | '35V'         | '20%'       | 'DISCRETE' | 'CAP ELEC 330U 35V(20%,105C,10*10)SMD'                 | 'SMT'          | ''          | ''            | '20200203'
 '330UF'  | '35V'   | '20%'       | 'SMLF'      | 'EMPTY'    | 'CC73305MZ24'(!)             = ''              | ''                 | 'CC73305MZ24'                |'EC178_394_394SXB'| '330UF'  | '35V'         | '20%'       | 'IO'       | 'CAP ELEC 330U 35V(20%,105C,10*10)SMD'                 | 'SMT'          | ''          | ''            | '20200203'
 '1500UF' | '16V'   | '20%'       | 'THLF'      | 'ALUM'     | 'CC81503MD00'(!)             = ''              | ''                 | 'CC81503MD00'                |'EC197_394_787XC'| '1500UF' | '16V'         | '20%'       | 'DISCRETE' | 'CAP DIP 1500U 16V(+-20%,105C,10*20)'                  | 'DIP'          | ''          | ''            | '20200213'
 '1500UF' | '16V'   | '20%'       | 'THLF'      | 'EMPTY'    | 'CC81503MD00'(!)             = ''              | ''                 | 'CC81503MD00'                |'EC197_394_787XC'| '1500UF' | '16V'         | '20%'       | 'IO'       | 'CAP DIP 1500U 16V(+-20%,105C,10*20)'                  | 'DIP'          | ''          | ''            | '20200213'
 '330UF'  | '2.5V'  | '20%'       | 'SMLF'      | 'POSCAP'   | 'CH733LMI602'(!)             = 'End of Design' | 'Comp-Approve'     | 'CH733LMI602'                |'TAJ_B2XA'| '330UF'  | '2.5V'        | '20%'       | 'DISCRETE' | 'CAP CHIP 330U 2.5V(+-20%,3528,POSCAP)NEC'             | 'SMT'          | ''          | ''            | '20200226'
 '330UF'  | '2.5V'  | '20%'       | 'SMLF'      | 'EMPTY'    | 'CH733LMI602'(!)             = 'End of Design' | 'Comp-Approve'     | 'CH733LMI602'                |'TAJ_B2XA'| '330UF'  | '2.5V'        | '20%'       | 'IO'       | 'CAP CHIP 330U 2.5V(+-20%,3528,POSCAP)NEC'             | 'SMT'          | ''          | ''            | '20200226'
 '330UF'  | '2.5V'  | '20%'       | 'SMLF'      | 'POSCAP'   | 'CH733LMI603'(!)             = ''              | ''                 | 'CH733LMI603'                |'TAJ_B2S'| '330UF'  | '2.5V'        | '20%'       | 'DISCRETE' | 'CAP CHIP 330U 2.5V(+-20%,3528,POSCAP)SAY'             | 'SMT'          | ''          | ''            | '20200226'
 '330UF'  | '2.5V'  | '20%'       | 'SMLF'      | 'EMPTY'    | 'CH733LMI603'(!)             = ''              | ''                 | 'CH733LMI603'                |'TAJ_B2S'| '330UF'  | '2.5V'        | '20%'       | 'IO'       | 'CAP CHIP 330U 2.5V(+-20%,3528,POSCAP)SAY'             | 'SMT'          | ''          | ''            | '20200226'
 '220UF'  | '6.3V'  | '20%'       | 'SMLF'      | 'POSCAP'   | 'CH7221MI802'(!)             = ''              | ''                 | 'CH7221MI802'                |'TAJ_D3L'| '220UF'  | '6.3V'        | '20%'       | 'DISCRETE' | 'CAPCHIP220U 6.3V(20%,POSCAP(TAN)7343)SAY'             | 'SMT'          | ''          | ''            | '20200302'
 '220UF'  | '6.3V'  | '20%'       | 'SMLF'      | 'EMPTY'    | 'CH7221MI802'(!)             = ''              | ''                 | 'CH7221MI802'                |'TAJ_D3L'| '220UF'  | '6.3V'        | '20%'       | 'IO'       | 'CAPCHIP220U 6.3V(20%,POSCAP(TAN)7343)SAY'             | 'SMT'          | ''          | ''            | '20200302'
 '47UF'   | '25V'   | '20%'       | 'SMLF'      | 'ALUM'     | 'CC64704MZ19'(!)             = ''              | ''                 | 'CC64704MZ19'                |'EC71_248_229SXA'| '47UF'   | '25V'         | '20%'       | 'DISCRETE' | 'CAP ELEC SMD 47U 25V(20%,6.3*5.8)MAT'                 | 'SMT'          | ''          | ''            | '20200305'
 '47UF'   | '25V'   | '20%'       | 'SMLF'      | 'EMPTY'    | 'CC64704MZ19'(!)             = ''              | ''                 | 'CC64704MZ19'                |'EC71_248_229SXA'| '47UF'   | '25V'         | '20%'       | 'IO'       | 'CAP ELEC SMD 47U 25V(20%,6.3*5.8)MAT'                 | 'SMT'          | ''          | ''            | '20200305'
 '100UF'  | '25V'   | '20%'       | 'SMLF'      | 'SPCAP'    | 'CH7104M8800'(!)             = 'End of Design' | 'End of Life'      | 'CH7104M8800'                |'TAJ_7343-20_H122_EOL'| '100UF'  | '25V'         | '20%'       | 'DISCRETE' | 'CAP CHIP 100U 25V(20%,SPCAP,7343)KEM'                 | 'SMT'          | ''          | ''            | '20200310'
 '100UF'  | '25V'   | '20%'       | 'SMLF'      | 'EMPTY'    | 'CH7104M8800'(!)             = 'End of Design' | 'End of Life'      | 'CH7104M8800'                |'TAJ_7343-20_H122_EOL'| '100UF'  | '25V'         | '20%'       | 'IO'       | 'CAP CHIP 100U 25V(20%,SPCAP,7343)KEM'                 | 'SMT'          | ''          | ''            | '20200310'
 '470UF'  | '6.3V'  | '20%'       | 'SMLF'      | 'POSCAP'   | 'CH7471MI806'(!)             = ''              | ''                 | 'CH7471MI806'                |'TAJ_D4XA_H158'| '470UF'  | '6.3V'        | '20%'       | 'DISCRETE' | 'CAPCHIP470U 6.3V(20%,POSCAP(TAN)7343)SAY'             | 'SMT'          | ''          | ''            | '20200311'
 '470UF'  | '6.3V'  | '20%'       | 'SMLF'      | 'EMPTY'    | 'CH7471MI806'(!)             = ''              | ''                 | 'CH7471MI806'                |'TAJ_D4XA_H158'| '470UF'  | '6.3V'        | '20%'       | 'IO'       | 'CAPCHIP470U 6.3V(20%,POSCAP(TAN)7343)SAY'             | 'SMT'          | ''          | ''            | '20200311'
 '270UF'  | '25V'   | '20%'       | 'SMLF'      | 'OSCON'    | 'CC72704MZ02'(!)             = ''              | ''                 | 'CC72704MZ02'                |'EC122_315_473S'| '270UF'  | '25V'         | '20%'       | 'DISCRETE' | 'CAP OSCON SMD 270U 25V(20%,125C,8*12)LLN'             | 'SMT'          | ''          | ''            | '20200311'
 '270UF'  | '25V'   | '20%'       | 'SMLF'      | 'EMPTY'    | 'CC72704MZ02'(!)             = ''              | ''                 | 'CC72704MZ02'                |'EC122_315_473S'| '270UF'  | '25V'         | '20%'       | 'IO'       | 'CAP OSCON SMD 270U 25V(20%,125C,8*12)LLN'             | 'SMT'          | ''          | ''            | '20200311'
 '560UF'  | '2V'    | '20%'       | 'SMLF'      | 'SPCAP'    | 'CH756RM8806'(!)             = ''              | ''                 | 'CH756RM8806'                |'TAJ_SX'| '560UF'  | '2V'          | '20%'       | 'DISCRETE' | 'CAPCHIP560U2V(20%,SPCAP,,ESR4.5,7343)MAT'             | 'SMT'          | ''          | ''            | '20200318'
 '560UF'  | '2V'    | '20%'       | 'SMLF'      | 'EMPTY'    | 'CH756RM8806'(!)             = ''              | ''                 | 'CH756RM8806'                |'TAJ_SX'| '560UF'  | '2V'          | '20%'       | 'IO'       | 'CAPCHIP560U2V(20%,SPCAP,,ESR4.5,7343)MAT'             | 'SMT'          | ''          | ''            | '20200318'
 '470UF'  | '2.5V'  | '20%'       | 'SMLF'      | 'SPCAP'    | 'CH747LM8818'(!)             = ''              | ''                 | 'CH747LM8818'                |'TAJ_DXC'| '470UF'  | '2.5V'        | '20%'       | 'DISCRETE' | 'CAP CHIP 470U 2.5V(+-20%,7343,SPCAP)MAT'              | 'SMT'          | ''          | ''            | '20200318'
 '470UF'  | '2.5V'  | '20%'       | 'SMLF'      | 'EMPTY'    | 'CH747LM8818'(!)             = ''              | ''                 | 'CH747LM8818'                |'TAJ_DXC'| '470UF'  | '2.5V'        | '20%'       | 'IO'       | 'CAP CHIP 470U 2.5V(+-20%,7343,SPCAP)MAT'              | 'SMT'          | ''          | ''            | '20200318'
 '330UF'  | '2.5V'  | '+10/-35%'  | 'SMLF'      | 'SPCAP'    | 'CH733LY8802'(!)             = ''              | ''                 | 'CH733LY8802'                |'TAJ_SX'| '330UF'  | '2.5V'        | '+10/-35%'  | 'DISCRETE' | 'CAPCHIP 330U 2.5V(10/-35%,SPCAP,7343)MAT'             | 'SMT'          | ''          | ''            | '20200326'
 '330UF'  | '2.5V'  | '+10/-35%'  | 'SMLF'      | 'EMPTY'    | 'CH733LY8802'(!)             = ''              | ''                 | 'CH733LY8802'                |'TAJ_SX'| '330UF'  | '2.5V'        | '+10/-35%'  | 'IO'       | 'CAPCHIP 330U 2.5V(10/-35%,SPCAP,7343)MAT'             | 'SMT'          | ''          | ''            | '20200326'
 '330UF'  | '10V'   | '20%'       | 'SMLF'      | 'TANT'     | 'CH7332MI800'(!)             = ''              | ''                 | 'CH7332MI800'                |'TAJ_7343-20_H170'| '330UF'  | '10V'         | '20%'       | 'DISCRETE' | 'CAPCHIP330U 10V(20%,POSCAP(TAN),7343)KEM'             | 'SMT'          | ''          | ''            | '20200407'
 '330UF'  | '10V'   | '20%'       | 'SMLF'      | 'EMPTY'    | 'CH7332MI800'(!)             = ''              | ''                 | 'CH7332MI800'                |'TAJ_7343-20_H170'| '330UF'  | '10V'         | '20%'       | 'IO'       | 'CAPCHIP330U 10V(20%,POSCAP(TAN),7343)KEM'             | 'SMT'          | ''          | ''            | '20200407'
 '330UF'  | '10V'   | '20%'       | 'SMLF'      | 'POSCAP'   | 'CH7332MI801'(!)             = ''              | ''                 | 'CH7332MI801'                |'TAJ_D4XB'| '330UF'  | '10V'         | '20%'       | 'DISCRETE' | 'CAPCHIP330U 10V(20%,POSCAP(TAN),7343)SAY'             | 'SMT'          | ''          | ''            | '20200406'
 '330UF'  | '10V'   | '20%'       | 'SMLF'      | 'EMPTY'    | 'CH7332MI801'(!)             = ''              | ''                 | 'CH7332MI801'                |'TAJ_D4XB'| '330UF'  | '10V'         | '20%'       | 'IO'       | 'CAPCHIP330U 10V(20%,POSCAP(TAN),7343)SAY'             | 'SMT'          | ''          | ''            | '20200406'
 '330UF'  | '10V'   | '20%'       | 'SMLF'      | 'POSCAP'   | 'CH7332M8804'(!)             = 'End of Design' | 'Comp-Approve'     | 'CH7332M8804'                |'TAJ_D4XB'| '330UF'  | '10V'         | '20%'       | 'DISCRETE' | 'CAP CHIP 330U 10V(20%,ESR25,7343,H4.0)'               | 'SMT'          | ''          | ''            | '20200406'
 '330UF'  | '10V'   | '20%'       | 'SMLF'      | 'EMPTY'    | 'CH7332M8804'(!)             = 'End of Design' | 'Comp-Approve'     | 'CH7332M8804'                |'TAJ_D4XB'| '330UF'  | '10V'         | '20%'       | 'IO'       | 'CAP CHIP 330U 10V(20%,ESR25,7343,H4.0)'               | 'SMT'          | ''          | ''            | '20200406'
 '270UF'  | '16V'   | '20%'       | 'THLF'      | 'OSCON'    | 'CC72703MD33'(!)             = ''              | ''                 | 'CC72703MD33'                |'EC2-5_6-8_9'| '270UF'  | '16V'         | '20%'       | 'DISCRETE' | 'CAP OSCON DIP 270U 16V(20%,,6.3*9)APQ'                | 'DIP'          | ''          | ''            | '20200416'
 '270UF'  | '16V'   | '20%'       | 'THLF'      | 'EMPTY'    | 'CC72703MD33'(!)             = ''              | ''                 | 'CC72703MD33'                |'EC2-5_6-8_9'| '270UF'  | '16V'         | '20%'       | 'IO'       | 'CAP OSCON DIP 270U 16V(20%,,6.3*9)APQ'                | 'DIP'          | ''          | ''            | '20200416'
 '560UF'  | '6.3V'  | '20%'       | 'THLF'      | 'OSCON'    | 'CC75601MD18'(!)             = ''              | ''                 | 'CC75601MD18'                |'EC2-5_6-8_9'| '560UF'  | '6.3V'        | '20%'       | 'DISCRETE' | 'CAP OSCON DIP 560U 6.3V(+-20%,6.3*9)APQ'              | 'DIP'          | ''          | ''            | '20200417'
 '560UF'  | '6.3V'  | '20%'       | 'THLF'      | 'EMPTY'    | 'CC75601MD18'(!)             = ''              | ''                 | 'CC75601MD18'                |'EC2-5_6-8_9'| '560UF'  | '6.3V'        | '20%'       | 'IO'       | 'CAP OSCON DIP 560U 6.3V(+-20%,6.3*9)APQ'              | 'DIP'          | ''          | ''            | '20200417'
 '560UF'  | '2.5V'  | '20%'       | 'THLF'      | 'OSCON'    | 'CC7560JMD18'(!)             = ''              | ''                 | 'CC7560JMD18'                |'EC2_5-5_9XA'| '560UF'  | '2.5V'        | '20%'       | 'DISCRETE' | 'CAP OSCON DIP 560U 2.5V(+-20%,5*9)APQ'                | 'DIP'          | ''          | ''            | '20200416'
 '560UF'  | '2.5V'  | '20%'       | 'THLF'      | 'EMPTY'    | 'CC7560JMD18'(!)             = ''              | ''                 | 'CC7560JMD18'                |'EC2_5-5_9XA'| '560UF'  | '2.5V'        | '20%'       | 'IO'       | 'CAP OSCON DIP 560U 2.5V(+-20%,5*9)APQ'                | 'DIP'          | ''          | ''            | '20200416'
 '100UF'  | '16V'   | '20%'       | 'SMLF'      | 'OSCON'    | 'CC71003MZ32'(!)             = ''              | ''                 | 'CC71003MZ32'                |'EC56_197_229S'| '100UF'  | '16V'         | '20%'       | 'DISCRETE' | 'CAP OSCON SMD 100U 16V(20%,5*5.8)APQ'                 | 'SMT'          | ''          | ''            | '20200715'
 '100UF'  | '16V'   | '20%'       | 'SMLF'      | 'EMPTY'    | 'CC71003MZ32'(!)             = ''              | ''                 | 'CC71003MZ32'                |'EC56_197_229S'| '100UF'  | '16V'         | '20%'       | 'IO'       | 'CAP OSCON SMD 100U 16V(20%,5*5.8)APQ'                 | 'SMT'          | ''          | ''            | '20200715'
 '2200UF' | '16V'   | '20%'       | 'THLF'      | 'OSCON'    | 'SP_CC82203MD07'(!)          = ''              | ''                 | 'CC82203MD07'                |'G_EC5_10-5_21-5XA'| '2200UF' | '16V'         | '20%'       | 'DISCRETE' | 'CAP OSCON DIP 2200U 16V(20%,10*20)NPN_FOR SEL'        | 'DIP'          | ''          | ''            | '20200731'
 '2200UF' | '16V'   | '20%'       | 'THLF'      | 'EMPTY'    | 'SP_CC82203MD07'(!)          = ''              | ''                 | 'CC82203MD07'                |'G_EC5_10-5_21-5XA'| '2200UF' | '16V'         | '20%'       | 'IO'       | 'CAP OSCON DIP 2200U 16V(20%,10*20)NPN_FOR SEL'        | 'DIP'          | ''          | ''            | '20200731'
 '330UF'  | '10V'   | '20%'       | 'SMLF'      | 'POSCAP'   | 'CH7332M8800'(!)             = 'End of Design' | 'Comp-Approve'     | 'CH7332M8800'                |'TAJ_7343-20_H170'| '330UF'  | '10V'         | '20%'       | 'DISCRETE' | 'CAP CHIP 330U 10V(20%,ESR6,7343,H4.0)'                | 'SMT'          | ''          | ''            | '20200917'
 '330UF'  | '10V'   | '20%'       | 'SMLF'      | 'EMPTY'    | 'CH7332M8800'(!)             = 'End of Design' | 'Comp-Approve'     | 'CH7332M8800'                |'TAJ_7343-20_H170'| '330UF'  | '10V'         | '20%'       | 'IO'       | 'CAP CHIP 330U 10V(20%,ESR6,7343,H4.0)'                | 'SMT'          | ''          | ''            | '20200917'
 '100UF'  | '10V'   | '20%'       | 'SMLF'      | 'POSCAP'   | 'CH7102M8808'(!)             = 'End of Design' | 'Comp-Approve'     | 'CH7102M8808'                |'TAJ_7343-20'| '100UF'  | '10V'         | '20%'       | 'DISCRETE' | 'CAP CHIP 100U 10V(20%,ESR45,7343,H1.9)'               | 'SMT'          | ''          | ''            | '20200922'
 '100UF'  | '10V'   | '20%'       | 'SMLF'      | 'EMPTY'    | 'CH7102M8808'(!)             = 'End of Design' | 'Comp-Approve'     | 'CH7102M8808'                |'TAJ_7343-20'| '100UF'  | '10V'         | '20%'       | 'IO'       | 'CAP CHIP 100U 10V(20%,ESR45,7343,H1.9)'               | 'SMT'          | ''          | ''            | '20200922'
 '330UF'  | '6.3V'  | '20%'       | 'SMLF'      | 'OSCON'    | 'CC73301MZ19'(!)             = ''              | ''                 | 'CC73301MZ19'                |'EC75_248_229SXA'| '330UF'  | '6.3V'        | '20%'       | 'DISCRETE' | 'CAP OSCON SMD 330U 6.3V(20%,6.3*5.8)NPN'              | 'SMT'          | ''          | ''            | '20201105'
 '330UF'  | '6.3V'  | '20%'       | 'SMLF'      | 'EMPTY'    | 'CC73301MZ19'(!)             = ''              | ''                 | 'CC73301MZ19'                |'EC75_248_229SXA'| '330UF'  | '6.3V'        | '20%'       | 'IO'       | 'CAP OSCON SMD 330U 6.3V(20%,6.3*5.8)NPN'              | 'SMT'          | ''          | ''            | '20201105'
 '470UF'  | '2.5V'  | '20%'       | 'SMLF'      | 'SPCAP'    | 'CH747LM8825'(!)             = ''              | ''                 | 'CH747LM8825'                |'TAJ_SX'| '470UF'  | '2.5V'        | '20%'       | 'DISCRETE' | 'CAPCHIP 470U 2.5V(20%,SP,ESR4.5,7343)MAT'             | 'SMT'          | ''          | ''            | '20201120'
 '470UF'  | '2.5V'  | '20%'       | 'SMLF'      | 'EMPTY'    | 'CH747LM8825'(!)             = ''              | ''                 | 'CH747LM8825'                |'TAJ_SX'| '470UF'  | '2.5V'        | '20%'       | 'IO'       | 'CAPCHIP 470U 2.5V(20%,SP,ESR4.5,7343)MAT'             | 'SMT'          | ''          | ''            | '20201120'
 '220UF'  | '6.3V'  | '+10/-35%'  | 'SMLF'      | 'SPCAP'    | 'CH7221Y8801'(!)             = ''              | ''                 | 'CH7221Y8801'                |'TAJ_DXC'| '220UF'  | '6.3V'        | '+10/-35%'  | 'DISCRETE' | 'CAP CHIP 220U 6.3V(+10/-35%,7343,SP)MAT'              | 'SMT'          | ''          | ''            | '20201203'
 '220UF'  | '6.3V'  | '+10/-35%'  | 'SMLF'      | 'EMPTY'    | 'CH7221Y8801'(!)             = ''              | ''                 | 'CH7221Y8801'                |'TAJ_DXC'| '220UF'  | '6.3V'        | '+10/-35%'  | 'IO'       | 'CAP CHIP 220U 6.3V(+10/-35%,7343,SP)MAT'              | 'SMT'          | ''          | ''            | '20201203'
 '220UF'  | '6.3V'  | '20%'       | 'SMLF'      | 'SPCAP'    | 'CH7221M8816'(!)             = ''              | ''                 | 'CH7221M8816'                |'TAJ_DXC'| '220UF'  | '6.3V'        | '20%'       | 'DISCRETE' | 'CAP CHIP 220U 6.3V(20%,SP,ESR15,7343)MAT'             | 'SMT'          | ''          | ''            | '20201203'
 '220UF'  | '6.3V'  | '20%'       | 'SMLF'      | 'EMPTY'    | 'CH7221M8816'(!)             = ''              | ''                 | 'CH7221M8816'                |'TAJ_DXC'| '220UF'  | '6.3V'        | '20%'       | 'IO'       | 'CAP CHIP 220U 6.3V(20%,SP,ESR15,7343)MAT'             | 'SMT'          | ''          | ''            | '20201203'
 '220UF'  | '6.3V'  | '20%'       | 'SMLF'      | 'POSCAP'   | 'CH7221MI804'(!)             = ''              | ''                 | 'CH7221MI804'                |'TAJ_D2EXA'| '220UF'  | '6.3V'        | '20%'       | 'DISCRETE' | 'CAPCHIP 220U 6.3V(20%,POS,ESR18,7343)SAY'             | 'SMT'          | ''          | ''            | '20201203'
 '220UF'  | '6.3V'  | '20%'       | 'SMLF'      | 'EMPTY'    | 'CH7221MI804'(!)             = ''              | ''                 | 'CH7221MI804'                |'TAJ_D2EXA'| '220UF'  | '6.3V'        | '20%'       | 'IO'       | 'CAPCHIP 220U 6.3V(20%,POS,ESR18,7343)SAY'             | 'SMT'          | ''          | ''            | '20201203'
 '390UF'  | '2.5V'  | '20%'       | 'SMLF'      | 'OSCON'    | 'CC7390JMZ12'(!)             = ''              | ''                 | 'CC7390JMZ12'                |'EC56_197_229SXA'| '390UF'  | '2.5V'        | '20%'       | 'DISCRETE' | 'CAP OSCON 390U 2.5V(20%,105C,5*5.8)APQ'               | 'SMT'          | ''          | ''            | '20201209'
 '390UF'  | '2.5V'  | '20%'       | 'SMLF'      | 'EMPTY'    | 'CC7390JMZ12'(!)             = ''              | ''                 | 'CC7390JMZ12'                |'EC56_197_229SXA'| '390UF'  | '2.5V'        | '20%'       | 'IO'       | 'CAP OSCON 390U 2.5V(20%,105C,5*5.8)APQ'               | 'SMT'          | ''          | ''            | '20201209'
 '220UF'  | '6.3V'  | '20%'       | 'SMLF'      | 'OSCON'    | 'CC72201MZ39'(!)             = ''              | ''                 | 'CC72201MZ39'                |'EC56_197_229SXA'| '220UF'  | '6.3V'        | '20%'       | 'DISCRETE' | 'CAP OSCON SMD 220U 6.3V(20%,5*5.8)APQ'                | 'SMT'          | ''          | ''            | '20201209'
 '220UF'  | '6.3V'  | '20%'       | 'SMLF'      | 'EMPTY'    | 'CC72201MZ39'(!)             = ''              | ''                 | 'CC72201MZ39'                |'EC56_197_229SXA'| '220UF'  | '6.3V'        | '20%'       | 'IO'       | 'CAP OSCON SMD 220U 6.3V(20%,5*5.8)APQ'                | 'SMT'          | ''          | ''            | '20201209'
 '270UF'  | '16V'   | '20%'       | 'SMLF'      | 'OSCON'    | 'CC72703MZ11'(!)             = ''              | ''                 | 'CC72703MZ11'                |'EC75_248_304S'| '270UF'  | '16V'         | '20%'       | 'DISCRETE' | 'CAP OSCON SMD 270U 16V(20%,6.3*7.7)NPN'               | 'SMT'          | ''          | ''            | '20201209'
 '270UF'  | '16V'   | '20%'       | 'SMLF'      | 'EMPTY'    | 'CC72703MZ11'(!)             = ''              | ''                 | 'CC72703MZ11'                |'EC75_248_304S'| '270UF'  | '16V'         | '20%'       | 'IO'       | 'CAP OSCON SMD 270U 16V(20%,6.3*7.7)NPN'               | 'SMT'          | ''          | ''            | '20201209'
 '270UF'  | '16V'   | '20%'       | 'SMLF'      | 'OSCON'    | 'CC72703MZ15'(!)             = ''              | ''                 | 'CC72703MZ15'                |'EC83_248_296S'| '270UF'  | '16V'         | '20%'       | 'DISCRETE' | 'CAP OSCON SMD 270U 16V(20%,6.3*7.5)APQ'               | 'SMT'          | ''          | ''            | '20201209'
 '270UF'  | '16V'   | '20%'       | 'SMLF'      | 'EMPTY'    | 'CC72703MZ15'(!)             = ''              | ''                 | 'CC72703MZ15'                |'EC83_248_296S'| '270UF'  | '16V'         | '20%'       | 'IO'       | 'CAP OSCON SMD 270U 16V(20%,6.3*7.5)APQ'               | 'SMT'          | ''          | ''            | '20201209'
 '68UF'   | '16V'   | '20%'       | 'SMLF'      | 'POSCAP'   | 'CH6683MI802'(!)             = ''              | 'P/N Release'      | 'CH6683MI802'                | 'TAJ_DXD_H79'              | '68UF'   | '16V'         | '20%'       | 'DISCRETE' | 'CAP CHIP 68U 16V(20%,ESR=50,7343,POS)NEC'             | 'SMT'          | ''          | ''            | '20201222'
 '68UF'   | '16V'   | '20%'       | 'SMLF'      | 'EMPTY'    | 'CH6683MI802'(!)             = ''              | 'P/N Release'      | 'CH6683MI802'                | 'TAJ_DXD_H79'              | '68UF'   | '16V'         | '20%'       | 'IO'       | 'CAP CHIP 68U 16V(20%,ESR=50,7343,POS)NEC'             | 'SMT'          | ''          | ''            | '20201222'
 '68UF'   | '16V'   | '20%'       | 'SMLF'      | 'POSCAP'   | 'CH6683MI804'(!)             = ''              | ''                 | 'CH6683MI804'                |'TAJ_V'| '68UF'   | '16V'         | '20%'       | 'DISCRETE' | 'CAP CHIP 68U 16V(20%,ESR50,7343,POS)KEM'              | 'SMT'          | ''          | ''            | '20201222'
 '68UF'   | '16V'   | '20%'       | 'SMLF'      | 'EMPTY'    | 'CH6683MI804'(!)             = ''              | ''                 | 'CH6683MI804'                |'TAJ_V'| '68UF'   | '16V'         | '20%'       | 'IO'       | 'CAP CHIP 68U 16V(20%,ESR50,7343,POS)KEM'              | 'SMT'          | ''          | ''            | '20201222'
 '68UF'   | '16V'   | '20%'       | 'SMLF'      | 'POSCAP'   | 'CH6683MI801'(!)             = ''              | 'P/N Release'      | 'CH6683MI801'                | 'TAJ_D2EXA_H79'            | '68UF'   | '16V'         | '20%'       | 'DISCRETE' | 'CAP CHIP 68U 16V(20%,ESR=50,7343,POS)SAY'             | 'SMT'          | ''          | ''            | '20201222'
 '68UF'   | '16V'   | '20%'       | 'SMLF'      | 'EMPTY'    | 'CH6683MI801'(!)             = ''              | 'P/N Release'      | 'CH6683MI801'                | 'TAJ_D2EXA_H79'            | '68UF'   | '16V'         | '20%'       | 'IO'       | 'CAP CHIP 68U 16V(20%,ESR=50,7343,POS)SAY'             | 'SMT'          | ''          | ''            | '20201222'
 '1000UF' | '63V'   | '20%'       | 'SMLF'      | 'ALUM'     | 'CC81007MZ00'(!)             = ''              | ''                 | 'CC81007MZ00'                |'EC264_709_847S'| '1000UF' | '63V'         | '20%'       | 'DISCRETE' | 'CAP ELEC SMD 1000U 63V(20%,18*21.5)'                  | 'SMT'          | ''          | ''            | '20201231'
 '1000UF' | '63V'   | '20%'       | 'SMLF'      | 'EMPTY'    | 'CC81007MZ00'(!)             = ''              | ''                 | 'CC81007MZ00'                |'EC264_709_847S'| '1000UF' | '63V'         | '20%'       | 'IO'       | 'CAP ELEC SMD 1000U 63V(20%,18*21.5)'                  | 'SMT'          | ''          | ''            | '20201231'
 '100UF'  | '16V'   | '20%'       | 'THLF'      | 'ALUM'     | 'SP_CC71003MD17_1'(!)        = ''              | ''                 | 'CC71003MD17'                |'G_EC2-5_6-8_6'| '100UF'  | '16V'         | '20%'       | 'DISCRETE' | 'CAP OSCON DIP 100U 16V(20%,6.3*6)NPN_FOR SEL'         | 'DIP'          | ''          | ''            | '20210118'
 '100UF'  | '16V'   | '20%'       | 'THLF'      | 'EMPTY'    | 'SP_CC71003MD17_1'(!)        = ''              | ''                 | 'CC71003MD17'                |'G_EC2-5_6-8_6'| '100UF'  | '16V'         | '20%'       | 'IO'       | 'CAP OSCON DIP 100U 16V(20%,6.3*6)NPN_FOR SEL'         | 'DIP'          | ''          | ''            | '20210118'
 '470UF'  | '2.5V'  | '20%'       | 'SMLF'      | 'SPCAP'    | 'CH747LM8823'(!)             = ''              | ''                 | 'CH747LM8823'                |'TAJ_7343-20_H83'| '470UF'  | '2.5V'        | '20%'       | 'DISCRETE' | 'CAP CHIP 470U 2.5V(+-20%,7343,SPCAP)KEM'              | 'SMT'          | ''          | ''            | '20210126'
 '470UF'  | '2.5V'  | '20%'       | 'SMLF'      | 'EMPTY'    | 'CH747LM8823'(!)             = ''              | ''                 | 'CH747LM8823'                |'TAJ_7343-20_H83'| '470UF'  | '2.5V'        | '20%'       | 'IO'       | 'CAP CHIP 470U 2.5V(+-20%,7343,SPCAP)KEM'              | 'SMT'          | ''          | ''            | '20210126'
 '470UF'  | '2.5V'  | '20%'       | 'SMLF'      | 'SPCAP'    | 'CH747LM8822'(!)             = ''              | ''                 | 'CH747LM8822'                |'TAJ_7343-20_H83'| '470UF'  | '2.5V'        | '20%'       | 'DISCRETE' | 'CAPCHIP 470U 2.5V(20%,SP,ESR4.5,7343)KEM'             | 'SMT'          | ''          | ''            | '20210126'
 '470UF'  | '2.5V'  | '20%'       | 'SMLF'      | 'EMPTY'    | 'CH747LM8822'(!)             = ''              | ''                 | 'CH747LM8822'                |'TAJ_7343-20_H83'| '470UF'  | '2.5V'        | '20%'       | 'IO'       | 'CAPCHIP 470U 2.5V(20%,SP,ESR4.5,7343)KEM'             | 'SMT'          | ''          | ''            | '20210126'
 '330UF'  | '2V'    | '+10-35%'   | 'SMLF'      | 'SPCAP'    | 'CH733RY8808'(!)             = ''              | ''                 | 'CH733RY8808'                |'TAJ_S'| '330UF'  | '2V'          | '+10-35%'   | 'DISCRETE' | 'CAP CHIP 330U 2V(+10-35%SPCAP7343)APQ'                | 'SMT'          | ''          | ''            | '20210127'
 '330UF'  | '2V'    | '+10-35%'   | 'SMLF'      | 'EMPTY'    | 'CH733RY8808'(!)             = ''              | ''                 | 'CH733RY8808'                |'TAJ_S'| '330UF'  | '2V'          | '+10-35%'   | 'IO'       | 'CAP CHIP 330U 2V(+10-35%SPCAP7343)APQ'                | 'SMT'          | ''          | ''            | '20210127'
 '680UF'  | '35V'   | '20%'       | 'SMLF'      | 'ALUM'     | 'CC76805MZ01'(!)             = ''              | ''                 | 'CC76805MZ01'                |'EC178_394_394SXA_H414'| '680UF'  | '35V'         | '20%'       | 'DISCRETE' | 'CAP ELEC SMD 680U 35V(20%,10*10)NPN'                  | 'SMT'          | ''          | ''            | '20210323'
 '680UF'  | '35V'   | '20%'       | 'SMLF'      | 'EMPTY'    | 'CC76805MZ01'(!)             = ''              | ''                 | 'CC76805MZ01'                |'EC178_394_394SXA_H414'| '680UF'  | '35V'         | '20%'       | 'IO'       | 'CAP ELEC SMD 680U 35V(20%,10*10)NPN'                  | 'SMT'          | ''          | ''            | '20210323'
 '2200UF' | '35V'   | '20%'       | 'SMLF'      | 'ALUM'     | 'CC82205MZ01'(!)             = ''              | ''                 | 'CC82205MZ01'                |'EC256_709_847S'| '2200UF' | '35V'         | '20%'       | 'DISCRETE' | 'CAP ELEC SMD 2200U 35V(20%,18*21.5)NPN'               | 'SMT'          | ''          | ''            | '20210323'
 '2200UF' | '35V'   | '20%'       | 'SMLF'      | 'EMPTY'    | 'CC82205MZ01'(!)             = ''              | ''                 | 'CC82205MZ01'                |'EC256_709_847S'| '2200UF' | '35V'         | '20%'       | 'IO'       | 'CAP ELEC SMD 2200U 35V(20%,18*21.5)NPN'               | 'SMT'          | ''          | ''            | '20210323'
 '330UF'  | '2.5V'  | '+10%~-35%' | 'SMLF'      | 'SPCAP'    | 'CH733LY8800'(!)             = ''              | ''                 | 'CH733LY8800'                | 'TAJ_DXD_H79'              | '330UF'  | '2.5V'        | '+10%~-35%' | 'DISCRETE' | 'CAP 330U 2.5V(+10%~-35%,SPCAP,ESR=9,7343'             | 'SMT'          | ''          | ''            | '20210427'
 '330UF'  | '2.5V'  | '+10%~-35%' | 'SMLF'      | 'EMPTY'    | 'CH733LY8800'(!)             = ''              | ''                 | 'CH733LY8800'                | 'TAJ_DXD_H79'              | '330UF'  | '2.5V'        | '+10%~-35%' | 'IO'       | 'CAP 330U 2.5V(+10%~-35%,SPCAP,ESR=9,7343'             | 'SMT'          | ''          | ''            | '20210427'
 '56UF'   | '80V'   | '20%'       | 'SMLF'      | 'ALUM'     | 'CC6560EMZ00'(!)             = ''              | ''                 | 'CC6560EMZ00'                |'EC178_394_394SXA_H414'| '56UF'   | '80V'         | '20%'       | 'DISCRETE' | 'CAP ELEC SMD 56UF 80V(20%,ESR33,10*10)'               | 'SMT'          | ''          | ''            | '20210503'
 '56UF'   | '80V'   | '20%'       | 'SMLF'      | 'EMPTY'    | 'CC6560EMZ00'(!)             = ''              | ''                 | 'CC6560EMZ00'                |'EC178_394_394SXA_H414'| '56UF'   | '80V'         | '20%'       | 'IO'       | 'CAP ELEC SMD 56UF 80V(20%,ESR33,10*10)'               | 'SMT'          | ''          | ''            | '20210503'
 '1000UF' | '100V'  | '20%'       | 'THLF'      | 'ALUM'     | 'CC81008MD01'(!)             = ''              | ''                 | 'CC81008MD01'                |'EC296_709_1398'| '1000UF' | '100V'        | '20%'       | 'DISCRETE' | 'CAPELECDIP 1000U100V(20%,18*35.5)MAT AEC'             | 'DIP'          | ''          | ''            | '20210504'
 '1000UF' | '100V'  | '20%'       | 'THLF'      | 'EMPTY'    | 'CC81008MD01'(!)             = ''              | ''                 | 'CC81008MD01'                |'EC296_709_1398'| '1000UF' | '100V'        | '20%'       | 'IO'       | 'CAPELECDIP 1000U100V(20%,18*35.5)MAT AEC'             | 'DIP'          | ''          | ''            | '20210504'
 '560UF'  | '2.5V'  | '20%'       | 'THLF'      | 'OSCON'    | 'CC7560JMD17'(!)             = ''              | ''                 | 'CC7560JMD17'                |'EC78_197_315XB'| '560UF'  | '2.5V'        | '20%'       | 'DISCRETE' | 'CAP OSCON DIP 560U 2.5V(20%,ESR7,5*8)TOW'             | 'DIP'          | ''          | ''            | '20210506'
 '560UF'  | '2.5V'  | '20%'       | 'THLF'      | 'EMPTY'    | 'CC7560JMD17'(!)             = ''              | ''                 | 'CC7560JMD17'                |'EC78_197_315XB'| '560UF'  | '2.5V'        | '20%'       | 'IO'       | 'CAP OSCON DIP 560U 2.5V(20%,ESR7,5*8)TOW'             | 'DIP'          | ''          | ''            | '20210506'
 '100UF'  | '16V'   | '20%'       | 'SMLF'      | 'ALUM'     | 'CC71003MZ37'(!)             = ''              | ''                 | 'CC71003MZ37'                |'EC56_197_229SXA'| '100UF'  | '16V'         | '20%'       | 'DISCRETE' | 'CAP OS SMD 100U 16V(20%,ESR27,5*5.7)TOW'              | 'SMT'          | ''          | ''            | '20210510'
 '100UF'  | '16V'   | '20%'       | 'SMLF'      | 'EMPTY'    | 'CC71003MZ37'(!)             = ''              | ''                 | 'CC71003MZ37'                |'EC56_197_229SXA'| '100UF'  | '16V'         | '20%'       | 'IO'       | 'CAP OS SMD 100U 16V(20%,ESR27,5*5.7)TOW'              | 'SMT'          | ''          | ''            | '20210510'
 '1500UF' | '4V'    | '20%'       | 'SMLF'      | 'OSCON'    | 'CC8150IMZ00'(!)             = ''              | ''                 | 'CC8150IMZ00'                |'EC181_394_390S'| '1500UF' | '4V'          | '20%'       | 'DISCRETE' | 'CAP OSCON SMD 1500UF 4V(20%,105C,10*10)'              | 'SMT'          | ''          | ''            | '20210512'
 '1500UF' | '4V'    | '20%'       | 'SMLF'      | 'EMPTY'    | 'CC8150IMZ00'(!)             = ''              | ''                 | 'CC8150IMZ00'                |'EC181_394_390S'| '1500UF' | '4V'          | '20%'       | 'IO'       | 'CAP OSCON SMD 1500UF 4V(20%,105C,10*10)'              | 'SMT'          | ''          | ''            | '20210512'
 '2200UF' | '80V'   | '20%'       | 'THLF'      | 'ALUM'     | 'CC8220EMD00'(!)             = ''              | ''                 | 'CC8220EMD00'                |'EC394_866_1772'| '2200UF' | '80V'         | '20%'       | 'DISCRETE' | 'CAP ELEC DIP 2200UF 80V(+-20%,22*45)'                 | 'DIP'          | ''          | ''            | '20210512'
 '2200UF' | '80V'   | '20%'       | 'THLF'      | 'EMPTY'    | 'CC8220EMD00'(!)             = ''              | ''                 | 'CC8220EMD00'                |'EC394_866_1772'| '2200UF' | '80V'         | '20%'       | 'IO'       | 'CAP ELEC DIP 2200UF 80V(+-20%,22*45)'                 | 'DIP'          | ''          | ''            | '20210512'
 '680UF'  | '80V'   | '20%'       | 'SMLF'      | 'ALUM'     | 'CC7680EMZ00'(!)             = ''              | ''                 | 'CC7680EMZ00'                |'EC256_709_847S'| '680UF'  | '80V'         | '20%'       | 'DISCRETE' | 'CAP ELEC SMD 680UF 80V(+-20%,18*21.5)'                | 'SMT'          | ''          | ''            | '20210514'
 '680UF'  | '80V'   | '20%'       | 'SMLF'      | 'EMPTY'    | 'CC7680EMZ00'(!)             = ''              | ''                 | 'CC7680EMZ00'                |'EC256_709_847S'| '680UF'  | '80V'         | '20%'       | 'IO'       | 'CAP ELEC SMD 680UF 80V(+-20%,18*21.5)'                | 'SMT'          | ''          | ''            | '20210514'
 '1000UF' | '2.5V'  | '20%'       | 'SMLF'      | 'POSCAP'   | 'CH810LMI800'(!)             = ''              | ''                 | 'CH810LMI800'                |'TAJ_D4XB'| '1000UF' | '2.5V'        | '20%'       | 'DISCRETE' | 'CAP CHIP 1000U 2.5V(+-20%,POSCAP,7343)'               | 'SMT'          | ''          | ''            | '20210519'
 '1000UF' | '2.5V'  | '20%'       | 'SMLF'      | 'EMPTY'    | 'CH810LMI800'(!)             = ''              | ''                 | 'CH810LMI800'                |'TAJ_D4XB'| '1000UF' | '2.5V'        | '20%'       | 'IO'       | 'CAP CHIP 1000U 2.5V(+-20%,POSCAP,7343)'               | 'SMT'          | ''          | ''            | '20210519'
 '2200UF' | '63V'   | '20%'       | 'THLF'      | 'ALUM'     | 'CC82207MD00'(!)             = ''              | ''                 | 'CC82207MD00'                |'EC296_709_1575'| '2200UF' | '63V'         | '20%'       | 'DISCRETE' | 'CAP ELEC DIP 2200U 63V(20%,18*40)'                    | 'DIP'          | ''          | ''            | '20210520'
 '2200UF' | '63V'   | '20%'       | 'THLF'      | 'EMPTY'    | 'CC82207MD00'(!)             = ''              | ''                 | 'CC82207MD00'                |'EC296_709_1575'| '2200UF' | '63V'         | '20%'       | 'IO'       | 'CAP ELEC DIP 2200U 63V(20%,18*40)'                    | 'DIP'          | ''          | ''            | '20210520'
 '2200UF' | '80V'   | '20%'       | 'THLF'      | 'ALUM'     | 'CC8220EMD01'(!)             = ''              | ''                 | 'CC8220EMD01'                |'EC296_709_1772'| '2200UF' | '80V'         | '20%'       | 'DISCRETE' | 'CAP ELEC DIP 2200UF 80V(+-20%,18*45)'                 | 'DIP'          | ''          | ''            | '20210527'
 '2200UF' | '80V'   | '20%'       | 'THLF'      | 'EMPTY'    | 'CC8220EMD01'(!)             = ''              | ''                 | 'CC8220EMD01'                |'EC296_709_1772'| '2200UF' | '80V'         | '20%'       | 'IO'       | 'CAP ELEC DIP 2200UF 80V(+-20%,18*45)'                 | 'DIP'          | ''          | ''            | '20210527'
 '2200UF' | '35V'   | '20%'       | 'SMLF'      | 'ALUM'     | 'CC82205MZ02'(!)             = ''              | ''                 | 'CC82205MZ02'                |'EC264_709_650S_H670'| '2200UF' | '35V'         | '20%'       | 'DISCRETE' | 'CAP ELEC SMD 2200UF 35V(20%,18*16.5)MAT'              | 'SMT'          | ''          | ''            | '20210601'
 '2200UF' | '35V'   | '20%'       | 'SMLF'      | 'EMPTY'    | 'CC82205MZ02'(!)             = ''              | ''                 | 'CC82205MZ02'                |'EC264_709_650S_H670'| '2200UF' | '35V'         | '20%'       | 'IO'       | 'CAP ELEC SMD 2200UF 35V(20%,18*16.5)MAT'              | 'SMT'          | ''          | ''            | '20210601'
 '100UF'  | '100V'  | '20%'       | 'THLF'      | 'ALUM'     | 'CC71008MD07'(!)             = ''              | ''                 | 'CC71008MD07'                |'EC5_10-5_21-5'| '100UF'  | '100V'        | '20%'       | 'DISCRETE' | 'CAP ELEC DIP 100U 100V(20%,10*20)NPN'                 | 'DIP'          | ''          | ''            | '20210622'
 '100UF'  | '100V'  | '20%'       | 'THLF'      | 'EMPTY'    | 'CC71008MD07'(!)             = ''              | ''                 | 'CC71008MD07'                |'EC5_10-5_21-5'| '100UF'  | '100V'        | '20%'       | 'IO'       | 'CAP ELEC DIP 100U 100V(20%,10*20)NPN'                 | 'DIP'          | ''          | ''            | '20210622'
 '3.3F'   | '3V'    | '-10/30%'   | 'THLF'      | ''         | 'CCB330KTD00'(!)             = ''              | ''                 | 'CCB330KTD00'                |'EC3-5_8-5_21'| '3.3F'   | '3V'          | '-10/30%'   | 'DISCRETE' | 'CAPELEC DIP 3.3F 3V(-10/30%,8.5*21)SUPER'             | 'DIP'          | ''          | ''            | '20210708'
 '3.3F'   | '3V'    | '-10/30%'   | 'THLF'      | 'EMPTY'    | 'CCB330KTD00'(!)             = ''              | ''                 | 'CCB330KTD00'                |'EC3-5_8-5_21'| '3.3F'   | '3V'          | '-10/30%'   | 'IO'       | 'CAPELEC DIP 3.3F 3V(-10/30%,8.5*21)SUPER'             | 'DIP'          | ''          | ''            | '20210708'
 '100UF'  | '100V'  | '20%'       | 'THLF'      | 'ALUM'     | 'CC71008MD10'(!)             = ''              | ''                 | 'CC71008MD10'                |'EC197_394_787XC_H867'| '100UF'  | '100V'        | '20%'       | 'DISCRETE' | 'CAP ELEC DIP 100U 100V(20%,10*20)NIC'                 | 'DIP'          | ''          | ''            | '20210726'
 '100UF'  | '100V'  | '20%'       | 'THLF'      | 'EMPTY'    | 'CC71008MD10'(!)             = ''              | ''                 | 'CC71008MD10'                |'EC197_394_787XC_H867'| '100UF'  | '100V'        | '20%'       | 'IO'       | 'CAP ELEC DIP 100U 100V(20%,10*20)NIC'                 | 'DIP'          | ''          | ''            | '20210726'
 '1800UF' | '80V'   | '20%'       | 'THLF'      | 'ALUM'     | 'CC8180EMD00'(!)             = ''              | ''                 | 'CC8180EMD00'                |'EC296_709_1575XA'| '1800UF' | '80V'         | '20%'       | 'DISCRETE' | 'CAP ELEC DIP1800U 80V(20%.105C,18*40)NPN'             | 'DIP'          | ''          | ''            | '20210909'
 '1800UF' | '80V'   | '20%'       | 'THLF'      | 'EMPTY'    | 'CC8180EMD00'(!)             = ''              | ''                 | 'CC8180EMD00'                |'EC296_709_1575XA'| '1800UF' | '80V'         | '20%'       | 'IO'       | 'CAP ELEC DIP1800U 80V(20%.105C,18*40)NPN'             | 'DIP'          | ''          | ''            | '20210909'
 '270UF'  | '16V'   | '20%'       | 'THLF'      | 'OSCON'    | 'CC72703MD27'(!)             = ''              | ''                 | 'CC72703MD27'                |'EC138_315_315XA'| '270UF'  | '16V'         | '20%'       | 'DISCRETE' | 'CAP OSCON DIP 270U 16V(+-20%,8*8)NPN'                 | 'DIP'          | ''          | ''            | '20210914'
 '270UF'  | '16V'   | '20%'       | 'THLF'      | 'EMPTY'    | 'CC72703MD27'(!)             = ''              | ''                 | 'CC72703MD27'                |'EC138_315_315XA'| '270UF'  | '16V'         | '20%'       | 'IO'       | 'CAP OSCON DIP 270U 16V(+-20%,8*8)NPN'                 | 'DIP'          | ''          | ''            | '20210914'
 '560UF'  | '2.5V'  | '20%'       | 'THLF'      | 'OSCON'    | 'CC7560JMD08'(!)             = ''              | ''                 | 'CC7560JMD08'                |'EC98_248_315XB'| '560UF'  | '2.5V'        | '20%'       | 'DISCRETE' | 'CAP OSCON 560U 2.5V(20%,105C,6.3*8)ESR5'              | 'DIP'          | ''          | ''            | '20210922'
 '560UF'  | '2.5V'  | '20%'       | 'THLF'      | 'EMPTY'    | 'CC7560JMD08'(!)             = ''              | ''                 | 'CC7560JMD08'                |'EC98_248_315XB'| '560UF'  | '2.5V'        | '20%'       | 'IO'       | 'CAP OSCON 560U 2.5V(20%,105C,6.3*8)ESR5'              | 'DIP'          | ''          | ''            | '20210922'
 '470UF'  | '16V'   | '20%'       | 'THLF'      | 'OSCON'    | 'CC74703MD26'(!)             = ''              | ''                 | 'CC74703MD26'                |'EC138_315_355'| '470UF'  | '16V'         | '20%'       | 'DISCRETE' | 'CAP OSCON DIP 470U 16V(20%,ESR16,8*9)APQ'             | 'DIP'          | ''          | ''            | '20210928'
 '470UF'  | '16V'   | '20%'       | 'THLF'      | 'EMPTY'    | 'CC74703MD26'(!)             = ''              | ''                 | 'CC74703MD26'                |'EC138_315_355'| '470UF'  | '16V'         | '20%'       | 'IO'       | 'CAP OSCON DIP 470U 16V(20%,ESR16,8*9)APQ'             | 'DIP'          | ''          | ''            | '20210928'
 '47UF'   | '100V'  | '20%'       | 'THLF'      | 'ALUM'     | 'CC64708MD03'(!)             = ''              | ''                 | 'CC64708MD03'                |'EC3-5_8-5_13'| '47UF'   | '100V'        | '20%'       | 'DISCRETE' | 'CAP ELEC DIP 47U100V(20%,105C,8*11.5)NPN'             | 'DIP'          | ''          | ''            | '20210930'
 '47UF'   | '100V'  | '20%'       | 'THLF'      | 'EMPTY'    | 'CC64708MD03'(!)             = ''              | ''                 | 'CC64708MD03'                |'EC3-5_8-5_13'| '47UF'   | '100V'        | '20%'       | 'IO'       | 'CAP ELEC DIP 47U100V(20%,105C,8*11.5)NPN'             | 'DIP'          | ''          | ''            | '20210930'
 '270UF'  | '80V'   | '20%'       | 'THLF'      | 'ALUM'     | 'CC7270EMD00'(!)             = ''              | ''                 | 'CC7270EMD00'                |'EC5_10-5_26-5'| '270UF'  | '80V'         | '20%'       | 'DISCRETE' | 'CAP ELEC DIP 270U 80V(20%,10*25)NPN'                  | 'DIP'          | ''          | ''            | '20210930'
 '270UF'  | '80V'   | '20%'       | 'THLF'      | 'EMPTY'    | 'CC7270EMD00'(!)             = ''              | ''                 | 'CC7270EMD00'                |'EC5_10-5_26-5'| '270UF'  | '80V'         | '20%'       | 'IO'       | 'CAP ELEC DIP 270U 80V(20%,10*25)NPN'                  | 'DIP'          | ''          | ''            | '20210930'
 '47UF'   | '100V'  | '20%'       | 'THLF'      | 'ALUM'     | 'CC64708MD06'(!)             = ''              | ''                 | 'CC64708MD06'                |'EC197_394_492'| '47UF'   | '100V'        | '20%'       | 'DISCRETE' | 'CAP ELEC DIP 47U 100V(20%,10*12.5)NPN'                | 'DIP'          | ''          | ''            | '20210930'
 '47UF'   | '100V'  | '20%'       | 'THLF'      | 'EMPTY'    | 'CC64708MD06'(!)             = ''              | ''                 | 'CC64708MD06'                |'EC197_394_492'| '47UF'   | '100V'        | '20%'       | 'IO'       | 'CAP ELEC DIP 47U 100V(20%,10*12.5)NPN'                | 'DIP'          | ''          | ''            | '20210930'
 '47UF'   | '100V'  | '20%'       | 'THLF'      | 'ALUM'     | 'CC64708MD04'(!)             = ''              | ''                 | 'CC64708MD04'                |'EC3-5_8-5_13'| '47UF'   | '100V'        | '20%'       | 'DISCRETE' | 'CAP ELEC DIP 47U100V(20%,105C,8*11.5)CSA'             | 'DIP'          | ''          | ''            | '20211013'
 '47UF'   | '100V'  | '20%'       | 'THLF'      | 'EMPTY'    | 'CC64708MD04'(!)             = ''              | ''                 | 'CC64708MD04'                |'EC3-5_8-5_13'| '47UF'   | '100V'        | '20%'       | 'IO'       | 'CAP ELEC DIP 47U100V(20%,105C,8*11.5)CSA'             | 'DIP'          | ''          | ''            | '20211013'
 '270UF'  | '80V'   | '20%'       | 'THLF'      | 'ALUM'     | 'CC7270EMD02'(!)             = ''              | ''                 | 'CC7270EMD02'                |'EC197_394_1044'| '270UF'  | '80V'         | '20%'       | 'DISCRETE' | 'CAP ELEC DIP 270U 80V(20%,10*25)CSA'                  | 'DIP'          | ''          | ''            | '20211013'
 '270UF'  | '80V'   | '20%'       | 'THLF'      | 'EMPTY'    | 'CC7270EMD02'(!)             = ''              | ''                 | 'CC7270EMD02'                |'EC197_394_1044'| '270UF'  | '80V'         | '20%'       | 'IO'       | 'CAP ELEC DIP 270U 80V(20%,10*25)CSA'                  | 'DIP'          | ''          | ''            | '20211013'
 '1800UF' | '80V'   | '20%'       | 'THLF'      | 'ALUM'     | 'CC8180EMD03'(!)             = ''              | ''                 | 'CC8180EMD03'                |'EC7-5_18-5_41-5'| '1800UF' | '80V'         | '20%'       | 'DISCRETE' | 'CAP ELEC DIP 1800U 80V(20%,105C,18*40)'               | 'DIP'          | ''          | ''            | '20211013'
 '1800UF' | '80V'   | '20%'       | 'THLF'      | 'EMPTY'    | 'CC8180EMD03'(!)             = ''              | ''                 | 'CC8180EMD03'                |'EC7-5_18-5_41-5'| '1800UF' | '80V'         | '20%'       | 'IO'       | 'CAP ELEC DIP 1800U 80V(20%,105C,18*40)'               | 'DIP'          | ''          | ''            | '20211013'
 '47UF'   | '100V'  | '20%'       | 'THLF'      | 'ALUM'     | 'CC64708MD05'(!)             = ''              | ''                 | 'CC64708MD05'                |'EC138_315_453XC'| '47UF'   | '100V'        | '20%'       | 'DISCRETE' | 'CAP ELEC DIP 47U100V(20%,105C,8*11.5)CPX'             | 'DIP'          | ''          | ''            | '20211014'
 '47UF'   | '100V'  | '20%'       | 'THLF'      | 'EMPTY'    | 'CC64708MD05'(!)             = ''              | ''                 | 'CC64708MD05'                |'EC138_315_453XC'| '47UF'   | '100V'        | '20%'       | 'IO'       | 'CAP ELEC DIP 47U100V(20%,105C,8*11.5)CPX'             | 'DIP'          | ''          | ''            | '20211014'
 '270UF'  | '80V'   | '20%'       | 'THLF'      | 'ALUM'     | 'CC7270EMD01'(!)             = ''              | ''                 | 'CC7270EMD01'                |'EC197_394_985XA'| '270UF'  | '80V'         | '20%'       | 'DISCRETE' | 'CAP ELEC DIP 270U 80V(20%,10*25)CPX'                  | 'DIP'          | ''          | ''            | '20211014'
 '270UF'  | '80V'   | '20%'       | 'THLF'      | 'EMPTY'    | 'CC7270EMD01'(!)             = ''              | ''                 | 'CC7270EMD01'                |'EC197_394_985XA'| '270UF'  | '80V'         | '20%'       | 'IO'       | 'CAP ELEC DIP 270U 80V(20%,10*25)CPX'                  | 'DIP'          | ''          | ''            | '20211014'
 '47UF'   | '100V'  | '20%'       | 'THLF'      | 'ALUM'     | 'CC64708MD07'(!)             = ''              | ''                 | 'CC64708MD07'                |'EC197_394_493'| '47UF'   | '100V'        | '20%'       | 'DISCRETE' | 'CAP ELEC DIP 47U 100V(20%,10*12.5)CPX'                | 'DIP'          | ''          | ''            | '20211014'
 '47UF'   | '100V'  | '20%'       | 'THLF'      | 'EMPTY'    | 'CC64708MD07'(!)             = ''              | ''                 | 'CC64708MD07'                |'EC197_394_493'| '47UF'   | '100V'        | '20%'       | 'IO'       | 'CAP ELEC DIP 47U 100V(20%,10*12.5)CPX'                | 'DIP'          | ''          | ''            | '20211014'
 '220UF'  | '4V'    | '20%'       | 'SMLF'      | 'SPCAP'    | 'CH122KM8801'(!)             = ''              | ''                 | 'CH122KM8801'                |'TAJ_SX'| '220UF'  | '4V'          | '20%'       | 'DISCRETE' | 'CAP CHIP 220U 4V(20%,7343,SPCAP)MAT'                  | 'SMT'          | ''          | ''            | '20211108'
 '220UF'  | '4V'    | '20%'       | 'SMLF'      | 'EMPTY'    | 'CH122KM8801'(!)             = ''              | ''                 | 'CH122KM8801'                |'TAJ_SX'| '220UF'  | '4V'          | '20%'       | 'IO'       | 'CAP CHIP 220U 4V(20%,7343,SPCAP)MAT'                  | 'SMT'          | ''          | ''            | '20211108'
 '220UF'  | '4V'    | '20%'       | 'SMLF'      | 'SPCAP'    | 'CH722KM8804'(!)             = ''              | ''                 | 'CH722KM8804'                |'TAJ_S_H87'| '220UF'  | '4V'          | '20%'       | 'DISCRETE' | 'CAP CHIP 220U 4V(+-20%,SPCAP,7343)APQ'                | 'SMT'          | ''          | ''            | '20220118'
 '220UF'  | '4V'    | '20%'       | 'SMLF'      | 'EMPTY'    | 'CH722KM8804'(!)             = ''              | ''                 | 'CH722KM8804'                |'TAJ_S_H87'| '220UF'  | '4V'          | '20%'       | 'IO'       | 'CAP CHIP 220U 4V(+-20%,SPCAP,7343)APQ'                | 'SMT'          | ''          | ''            | '20220118'
 '330UF'  | '2.5V'  | '20%'       | 'SMLF'      | 'SPCAP'    | 'CH733LM8817'(!)             = ''              | ''                 | 'CH733LM8817'                |'TAJ_SX'| '330UF'  | '2.5V'        | '20%'       | 'DISCRETE' | 'CAP CHIP 330U 2.5V(20%,SPCAP,7343)MAT'                | 'SMT'          | ''          | ''            | '20220121'
 '330UF'  | '2.5V'  | '20%'       | 'SMLF'      | 'EMPTY'    | 'CH733LM8817'(!)             = ''              | ''                 | 'CH733LM8817'                |'TAJ_SX'| '330UF'  | '2.5V'        | '20%'       | 'IO'       | 'CAP CHIP 330U 2.5V(20%,SPCAP,7343)MAT'                | 'SMT'          | ''          | ''            | '20220121'
 '330UF'  | '2.5V'  | '20%'       | 'SMLF'      | 'POSCAP'   | 'CH733LMI804'(!)             = ''              | ''                 | 'CH733LMI804'                |'TAJ_7343-20'| '330UF'  | '2.5V'        | '20%'       | 'DISCRETE' | 'CAPCHIP 330U2.5V(20%,POSCAP(TAN)7343)KEM'             | 'SMT'          | ''          | ''            | '20220124'
 '330UF'  | '2.5V'  | '20%'       | 'SMLF'      | 'EMPTY'    | 'CH733LMI804'(!)             = ''              | ''                 | 'CH733LMI804'                |'TAJ_7343-20'| '330UF'  | '2.5V'        | '20%'       | 'IO'       | 'CAPCHIP 330U2.5V(20%,POSCAP(TAN)7343)KEM'             | 'SMT'          | ''          | ''            | '20220124'
 '1000UF' | '80V'   | '20%'       | 'THLF'      | 'ALUM'     | 'CC8100EMD00'(!)             = ''              | ''                 | 'CC8100EMD00'                |'EC7-5_18-5_26-5'| '1000UF' | '80V'         | '20%'       | 'DISCRETE' | 'CAP ELEC DIP 1000UF 80V(+-20%,18*25)'                 | 'DIP'          | ''          | ''            | '20220124'
 '1000UF' | '80V'   | '20%'       | 'THLF'      | 'EMPTY'    | 'CC8100EMD00'(!)             = ''              | ''                 | 'CC8100EMD00'                |'EC7-5_18-5_26-5'| '1000UF' | '80V'         | '20%'       | 'IO'       | 'CAP ELEC DIP 1000UF 80V(+-20%,18*25)'                 | 'DIP'          | ''          | ''            | '20220124'
 '470UF'  | '16V'   | '20%'       | 'SMLF'      | 'OSCON'    | 'CC74703MD22'(!)             = ''              | ''                 | 'CC74703MD22'                |'EC181_394_496SXA'| '470UF'  | '16V'         | '20%'       | 'DISCRETE' | 'CAP OSCON SMD 470UF 16V(20%,10*12.4)TOW'              | 'SMT'          | ''          | ''            | '20220125'
 '470UF'  | '16V'   | '20%'       | 'SMLF'      | 'EMPTY'    | 'CC74703MD22'(!)             = ''              | ''                 | 'CC74703MD22'                |'EC181_394_496SXA'| '470UF'  | '16V'         | '20%'       | 'IO'       | 'CAP OSCON SMD 470UF 16V(20%,10*12.4)TOW'              | 'SMT'          | ''          | ''            | '20220125'
 '220UF'  | '2.5V'  | '20%'       | 'SMLF'      | 'TANT'     | 'CH722LM8613'(!)             = ''              | ''                 | 'CH722LM8613'                |'TAJ_B_T520B227M2R5ATE015'| '220UF'  | '2.5V'        | '20%'       | 'DISCRETE' | 'CAP CHIP 220U 2.5V(+-20%,ESR15,3528)H1.9'             | 'SMT'          | ''          | ''            | '20220223'
 '220UF'  | '2.5V'  | '20%'       | 'SMLF'      | 'EMPTY'    | 'CH722LM8613'(!)             = ''              | ''                 | 'CH722LM8613'                |'TAJ_B_T520B227M2R5ATE015'| '220UF'  | '2.5V'        | '20%'       | 'IO'       | 'CAP CHIP 220U 2.5V(+-20%,ESR15,3528)H1.9'             | 'SMT'          | ''          | ''            | '20220223'
 '560UF'  | '6.3V'  | '20%'       | 'SMLF'      | 'OSCON'    | 'CC75601MZ00'(!)             = ''              | ''                 | 'CC75601MZ00'                |'EC75_248_304S'| '560UF'  | '6.3V'        | '20%'       | 'DISCRETE' | 'CAP OSCON SMD 560U 6.3V(20%,6.3*7.7)'                 | 'SMT'          | ''          | ''            | '20220329'
 '560UF'  | '6.3V'  | '20%'       | 'SMLF'      | 'EMPTY'    | 'CC75601MZ00'(!)             = ''              | ''                 | 'CC75601MZ00'                |'EC75_248_304S'| '560UF'  | '6.3V'        | '20%'       | 'IO'       | 'CAP OSCON SMD 560U 6.3V(20%,6.3*7.7)'                 | 'SMT'          | ''          | ''            | '20220329'
 '270UF'  | '16V'   | '20%'       | 'SMLF'      | 'OSCON'    | 'CC72703MZ13'(!)             = ''              | ''                 | 'CC72703MZ13'                |'EC83_248_315S'| '270UF'  | '16V'         | '20%'       | 'DISCRETE' | 'CAPOS SMD 270U 16V(20%,ESR10,6.3*7.9)SAY'             | 'SMT'          | ''          | ''            | '20220413'
 '270UF'  | '16V'   | '20%'       | 'SMLF'      | 'EMPTY'    | 'CC72703MZ13'(!)             = ''              | ''                 | 'CC72703MZ13'                |'EC83_248_315S'| '270UF'  | '16V'         | '20%'       | 'IO'       | 'CAPOS SMD 270U 16V(20%,ESR10,6.3*7.9)SAY'             | 'SMT'          | ''          | ''            | '20220413'
 '470UF'  | '16V'   | '20%'       | 'SMLF'      | 'OSCON'    | 'CC74703MZ07'(!)             = ''              | ''                 | 'CC74703MZ07'                |'EC181_394_496SXA'| '470UF'  | '16V'         | '20%'       | 'DISCRETE' | 'CAP OSCON SMD 470UF 16V(20%,10*12.6)SAY'              | 'SMT'          | ''          | ''            | '20220422'
 '470UF'  | '16V'   | '20%'       | 'SMLF'      | 'EMPTY'    | 'CC74703MZ07'(!)             = ''              | ''                 | 'CC74703MZ07'                |'EC181_394_496SXA'| '470UF'  | '16V'         | '20%'       | 'IO'       | 'CAP OSCON SMD 470UF 16V(20%,10*12.6)SAY'              | 'SMT'          | ''          | ''            | '20220422'
 '100UF'  | '100V'  | '20%'       | 'THLF'      | 'ALUM'     | 'SP_CC71008MD07'(!)          = ''              | ''                 | 'CC71008MD07'                |'G_EC5_10-5_21-5'| '100UF'  | '100V'        | '20%'       | 'DISCRETE' | 'CAP ELEC DIP 100U 100V(20%,10*20)NPN_FOR SEL'         | 'DIP'          | ''          | ''            | '20220518'
 '100UF'  | '100V'  | '20%'       | 'THLF'      | 'EMPTY'    | 'SP_CC71008MD07'(!)          = ''              | ''                 | 'CC71008MD07'                |'G_EC5_10-5_21-5'| '100UF'  | '100V'        | '20%'       | 'IO'       | 'CAP ELEC DIP 100U 100V(20%,10*20)NPN_FOR SEL'         | 'DIP'          | ''          | ''            | '20220518'
 '470UF'  | '16V'   | '20%'       | 'THLF'      | 'OSCON'    | 'CC74703MD25'(!)             = ''              | ''                 | 'CC74703MD25'                |'EC3-5_8-5_9'| '470UF'  | '16V'         | '20%'       | 'DISCRETE' | 'CAP OSCON DIP 470U 16V(20%,ESR16,8*8)NPN'             | 'DIP'          | ''          | ''            | '20220601'
 '470UF'  | '16V'   | '20%'       | 'THLF'      | 'EMPTY'    | 'CC74703MD25'(!)             = ''              | ''                 | 'CC74703MD25'                |'EC3-5_8-5_9'| '470UF'  | '16V'         | '20%'       | 'IO'       | 'CAP OSCON DIP 470U 16V(20%,ESR16,8*8)NPN'             | 'DIP'          | ''          | ''            | '20220601'
 '270UF'  | '25V'   | '20%'       | 'SMLF'      | 'OSCON'    | 'CC72704MZ00'(!)             = ''              | ''                 | 'CC72704MZ00'                |'EC126_315_469SXA'| '270UF'  | '25V'         | '20%'       | 'DISCRETE' | 'CAP OSCON 270U,25V(20%,125C,8*11.9)SAY'               | 'SMT'          | ''          | ''            | '20220701'
 '270UF'  | '25V'   | '20%'       | 'SMLF'      | 'EMPTY'    | 'CC72704MZ00'(!)             = ''              | ''                 | 'CC72704MZ00'                |'EC126_315_469SXA'| '270UF'  | '25V'         | '20%'       | 'IO'       | 'CAP OSCON 270U,25V(20%,125C,8*11.9)SAY'               | 'SMT'          | ''          | ''            | '20220701'
 '680UF'  | '2.5V'  | '20%'       | 'SMLF'      | 'POSCAP'   | 'CH768LMI802'(!)             = ''              | ''                 | 'CH768LMI802'                |'TAJ_7343-20_H122'| '680UF'  | '2.5V'        | '20%'       | 'DISCRETE' | 'CAPCHIP 680U2.5V(20%,POSCAP(TAN)7343)KEM'             | 'SMT'          | ''          | ''            | '20220928'
 '680UF'  | '2.5V'  | '20%'       | 'SMLF'      | 'EMPTY'    | 'CH768LMI802'(!)             = ''              | ''                 | 'CH768LMI802'                |'TAJ_7343-20_H122'| '680UF'  | '2.5V'        | '20%'       | 'IO'       | 'CAPCHIP 680U2.5V(20%,POSCAP(TAN)7343)KEM'             | 'SMT'          | ''          | ''            | '20220928'
 '470UF'  | '2.5V'  | '20%'       | 'SMLF'      | 'SPCAP'    | 'CH747LM8827'(!)             = ''              | ''                 | 'CH747LM8827'                |'TAJ_S'| '470UF'  | '2.5V'        | '20%'       | 'DISCRETE' | 'CAP CHIP 470U 2.5V(+-20%,7343,SPCAP)APQ'              | 'SMT'          | ''          | ''            | '20221114'
 '470UF'  | '2.5V'  | '20%'       | 'SMLF'      | 'EMPTY'    | 'CH747LM8827'(!)             = ''              | ''                 | 'CH747LM8827'                |'TAJ_S'| '470UF'  | '2.5V'        | '20%'       | 'IO'       | 'CAP CHIP 470U 2.5V(+-20%,7343,SPCAP)APQ'              | 'SMT'          | ''          | ''            | '20221114'
 '220UF'  | '6.3V'  | '20%'       | 'SMLF'      | 'SPCAP'    | 'CH7221M8818'(!)             = ''              | ''                 | 'CH7221M8818'                |'TAJ_S'| '220UF'  | '6.3V'        | '20%'       | 'DISCRETE' | 'CAP CHIP 220UF 6.3V(20%,SPCAP,7343)APQ'               | 'SMT'          | ''          | ''            | '20221114'
 '220UF'  | '6.3V'  | '20%'       | 'SMLF'      | 'EMPTY'    | 'CH7221M8818'(!)             = ''              | ''                 | 'CH7221M8818'                |'TAJ_S'| '220UF'  | '6.3V'        | '20%'       | 'IO'       | 'CAP CHIP 220UF 6.3V(20%,SPCAP,7343)APQ'               | 'SMT'          | ''          | ''            | '20221114'
 '680UF'  | '80V'   | '20%'       | 'SMLF'      | 'ALUM'     | 'CC7680EMZ01'(!)             = ''              | ''                 | 'CC7680EMZ01'                |'EC256_709_847S'| '680UF'  | '80V'         | '20%'       | 'DISCRETE' | 'CAP ELEC SMD 680UF 80V(+-20%,18*21.5)'                | 'SMT'          | ''          | ''            | '20221123'
 '680UF'  | '80V'   | '20%'       | 'SMLF'      | 'EMPTY'    | 'CC7680EMZ01'(!)             = ''              | ''                 | 'CC7680EMZ01'                |'EC256_709_847S'| '680UF'  | '80V'         | '20%'       | 'IO'       | 'CAP ELEC SMD 680UF 80V(+-20%,18*21.5)'                | 'SMT'          | ''          | ''            | '20221123'
 '270UF'  | '25V'   | '20%'       | 'SMLF'      | 'OSCON'    | 'CC72704MZ06'(!)             = ''              | ''                 | 'CC72704MZ06'                |'EC126_315_473S'| '270UF'  | '25V'         | '20%'       | 'DISCRETE' | 'CAP OSCON SMD 270U 25V(20%,105C,8*12)APQ'             | 'SMT'          | ''          | ''            | '20221123'
 '270UF'  | '25V'   | '20%'       | 'SMLF'      | 'EMPTY'    | 'CC72704MZ06'(!)             = ''              | ''                 | 'CC72704MZ06'                |'EC126_315_473S'| '270UF'  | '25V'         | '20%'       | 'IO'       | 'CAP OSCON SMD 270U 25V(20%,105C,8*12)APQ'             | 'SMT'          | ''          | ''            | '20221123'
 '270UF'  | '16V'   | '20%'       | 'SMLF'      | 'OSCON'    | 'CC72703MZ16'(!)             = ''              | ''                 | 'CC72703MZ16'                |'EC83_248_315S'| '270UF'  | '16V'         | '20%'       | 'DISCRETE' | 'CAP OS SMD 270U16V(20%,ESR13,6.3*7.7)CSA'             | 'SMT'          | ''          | ''            | '20221214'
 '270UF'  | '16V'   | '20%'       | 'SMLF'      | 'EMPTY'    | 'CC72703MZ16'(!)             = ''              | ''                 | 'CC72703MZ16'                |'EC83_248_315S'| '270UF'  | '16V'         | '20%'       | 'IO'       | 'CAP OS SMD 270U16V(20%,ESR13,6.3*7.7)CSA'             | 'SMT'          | ''          | ''            | '20221214'
 '220UF'  | '6.3V'  | '20%'       | 'SMLF'      | 'OSCON'    | 'CC72201MZ40'(!)             = ''              | ''                 | 'CC72201MZ40'                |'EC56_197_229SXA'| '220UF'  | '6.3V'        | '20%'       | 'DISCRETE' | 'CAP OS SMD 220U6.3V(20%,ESR12,5*5.7)CSA'              | 'SMT'          | ''          | ''            | '20221214'
 '220UF'  | '6.3V'  | '20%'       | 'SMLF'      | 'EMPTY'    | 'CC72201MZ40'(!)             = ''              | ''                 | 'CC72201MZ40'                |'EC56_197_229SXA'| '220UF'  | '6.3V'        | '20%'       | 'IO'       | 'CAP OS SMD 220U6.3V(20%,ESR12,5*5.7)CSA'              | 'SMT'          | ''          | ''            | '20221214'
 '390UF'  | '2.5V'  | '20%'       | 'SMLF'      | 'OSCON'    | 'CC7390JMZ15'(!)             = ''              | ''                 | 'CC7390JMZ15'                |'EC56_197_229SXA'| '390UF'  | '2.5V'        | '20%'       | 'DISCRETE' | 'CAP OS SMD 390U 2.5V(20%,ESR10,5*5.7)CSA'             | 'SMT'          | ''          | ''            | '20221214'
 '390UF'  | '2.5V'  | '20%'       | 'SMLF'      | 'EMPTY'    | 'CC7390JMZ15'(!)             = ''              | ''                 | 'CC7390JMZ15'                |'EC56_197_229SXA'| '390UF'  | '2.5V'        | '20%'       | 'IO'       | 'CAP OS SMD 390U 2.5V(20%,ESR10,5*5.7)CSA'             | 'SMT'          | ''          | ''            | '20221214'
 '470UF'  | '2V'    | '20%'       | 'SMLF'      | 'SPCAP'    | 'CH747RM8826'(!)             = ''              | ''                 | 'CH747RM8826'                |'TAJ_7343-20_H83'| '470UF'  | '2V'          | '20%'       | 'DISCRETE' | 'CAP CHIP 470U 2V(20%,SPCAP,ESR3,7343)KEM'             | 'SMT'          | ''          | ''            | '20221214'
 '470UF'  | '2V'    | '20%'       | 'SMLF'      | 'EMPTY'    | 'CH747RM8826'(!)             = ''              | ''                 | 'CH747RM8826'                |'TAJ_7343-20_H83'| '470UF'  | '2V'          | '20%'       | 'IO'       | 'CAP CHIP 470U 2V(20%,SPCAP,ESR3,7343)KEM'             | 'SMT'          | ''          | ''            | '20221214'
 '330UF'  | '2V'    | '20%'       | 'SMLF'      | 'SPCAP'    | 'CH733RM8830'(!)             = ''              | ''                 | 'CH733RM8830'                |'TAJ_7343-20'| '330UF'  | '2V'          | '20%'       | 'DISCRETE' | 'CAP CHIP 330U 2V(+-20%,SPCAP,7343)KEM'                | 'SMT'          | ''          | ''            | '20221226'
 '330UF'  | '2V'    | '20%'       | 'SMLF'      | 'EMPTY'    | 'CH733RM8830'(!)             = ''              | ''                 | 'CH733RM8830'                |'TAJ_7343-20'| '330UF'  | '2V'          | '20%'       | 'IO'       | 'CAP CHIP 330U 2V(+-20%,SPCAP,7343)KEM'                | 'SMT'          | ''          | ''            | '20221226'
 '220UF'  | '4V'    | '20%'       | 'SMLF'      | 'POSCAP'   | 'CH722KMI801'(!)             = ''              | ''                 | 'CH722KMI801'                |'TAJ_7343-20'| '220UF'  | '4V'          | '20%'       | 'DISCRETE' | 'CAP CHIP 220U 4V(20%,POSCAP(TAN,7343)KEM'             | 'SMT'          | ''          | ''            | '20230119'
 '220UF'  | '4V'    | '20%'       | 'SMLF'      | 'EMPTY'    | 'CH722KMI801'(!)             = ''              | ''                 | 'CH722KMI801'                |'TAJ_7343-20'| '220UF'  | '4V'          | '20%'       | 'IO'       | 'CAP CHIP 220U 4V(20%,POSCAP(TAN,7343)KEM'             | 'SMT'          | ''          | ''            | '20230119'
 '560UF'  | '2V'    | '20%'       | 'SMLF'      | 'SPCAP'    | 'CH756RM8805'(!)             = ''              | 'Comp-Approve'     | 'CH756RM8805'                | 'TAJ_DXC'                  | '560UF'  | '2V'          | '20%'       | 'DISCRETE' | 'CAPCHIP 560U 2V(20%,SPCAP,ESR=3,7343)MAT'             | 'SMT'          | ''          | ''            | '20230201'
 '560UF'  | '2V'    | '20%'       | 'SMLF'      | 'EMPTY'    | 'CH756RM8805'(!)             = ''              | 'Comp-Approve'     | 'CH756RM8805'                | 'TAJ_DXC'                  | '560UF'  | '2V'          | '20%'       | 'IO'       | 'CAPCHIP 560U 2V(20%,SPCAP,ESR=3,7343)MAT'             | 'SMT'          | ''          | ''            | '20230201'
 '1500UF' | '2.5V'  | '20%'       | 'SMLF'      | 'POSCAP'   | 'CH815LMI800'(!)             = ''              | ''                 | 'CH815LMI800'                |'TAJ_7343-20_H170'| '1500UF' | '2.5V'        | '20%'       | 'DISCRETE' | 'CAP CHIP 1500U 2.5V(20%,POSCAP,7343)'                 | 'SMT'          | ''          | ''            | '20230328'
 '1500UF' | '2.5V'  | '20%'       | 'SMLF'      | 'EMPTY'    | 'CH815LMI800'(!)             = ''              | ''                 | 'CH815LMI800'                |'TAJ_7343-20_H170'| '1500UF' | '2.5V'        | '20%'       | 'IO'       | 'CAP CHIP 1500U 2.5V(20%,POSCAP,7343)'                 | 'SMT'          | ''          | ''            | '20230328'
 '1000UF' | '16V'   | '20%'       | 'SMLF'      | 'OSCON'    | 'CC81003MZ06'(!)             = ''              | ''                 | 'CC81003MZ06'                |'EC181_394_496SXA'| '1000UF' | '16V'         | '20%'       | 'DISCRETE' | 'CAP OSCON SMD 1000U 16V(20%10*12.3)APQ'               | 'SMT'          | ''          | ''            | '20230324'
 '1000UF' | '16V'   | '20%'       | 'SMLF'      | 'EMPTY'    | 'CC81003MZ06'(!)             = ''              | ''                 | 'CC81003MZ06'                |'EC181_394_496SXA'| '1000UF' | '16V'         | '20%'       | 'IO'       | 'CAP OSCON SMD 1000U 16V(20%10*12.3)APQ'               | 'SMT'          | ''          | ''            | '20230324'
 '220UF'  | '16V'   | '20%'       | 'SMLF'      | 'POSCAP'   | 'CH7223MI800'(!)             = ''              | ''                 | 'CH7223MI800'                |'TAJ_D2EXA_H119'| '220UF'  | '16V'         | '20%'       | 'DISCRETE' | 'CAP CHIP 220U 16V(20%,POSCAP(TAN),7343)'              | 'SMT'          | ''          | ''            | '20230510'
 '220UF'  | '16V'   | '20%'       | 'SMLF'      | 'EMPTY'    | 'CH7223MI800'(!)             = ''              | ''                 | 'CH7223MI800'                |'TAJ_D2EXA_H119'| '220UF'  | '16V'         | '20%'       | 'IO'       | 'CAP CHIP 220U 16V(20%,POSCAP(TAN),7343)'              | 'SMT'          | ''          | ''            | '20230510'
 '220UF'  | '16V'   | '20%'       | 'SMLF'      | 'POSCAP'   | 'CH7223MI801'(!)             = ''              | ''                 | 'CH7223MI801'                |'TAJ_7343-20_H170'| '220UF'  | '16V'         | '20%'       | 'DISCRETE' | 'CAP CHIP 220U 16V(20%,POSCAP,7343,H4)'                | 'SMT'          | ''          | ''            | '20230511'
 '220UF'  | '16V'   | '20%'       | 'SMLF'      | 'EMPTY'    | 'CH7223MI801'(!)             = ''              | ''                 | 'CH7223MI801'                |'TAJ_7343-20_H170'| '220UF'  | '16V'         | '20%'       | 'IO'       | 'CAP CHIP 220U 16V(20%,POSCAP,7343,H4)'                | 'SMT'          | ''          | ''            | '20230511'
 '47UF'   | '16V'   | '20%'       | 'SMLF'      | 'SPCAP'    | 'CH6473M8808'(!)             = ''              | ''                 | 'CH6473M8808'                |'TAJ_D3XA'| '47UF'   | '16V'         | '20%'       | 'DISCRETE' | 'CAP CHIP 47U 16V(20%,SPCAP,105C,7343)MUR'             | 'SMT'          | ''          | ''            | '20230517'
 '47UF'   | '16V'   | '20%'       | 'SMLF'      | 'EMPTY'    | 'CH6473M8808'(!)             = ''              | ''                 | 'CH6473M8808'                |'TAJ_D3XA'| '47UF'   | '16V'         | '20%'       | 'IO'       | 'CAP CHIP 47U 16V(20%,SPCAP,105C,7343)MUR'             | 'SMT'          | ''          | ''            | '20230517'
 '1000UF' | '80V'   | '20%'       | 'THLF'      | 'ALUM'     | 'CC8100EMD02'(!)             = ''              | ''                 | 'CC8100EMD02'                |'EC7-5_18-5_27'| '1000UF' | '80V'         | '20%'       | 'DISCRETE' | 'CAP ELEC DIP 1000UF 80V(+-20%,18*25)CSA'              | 'DIP'          | ''          | ''            | '20230531'
 '1000UF' | '80V'   | '20%'       | 'THLF'      | 'EMPTY'    | 'CC8100EMD02'(!)             = ''              | ''                 | 'CC8100EMD02'                |'EC7-5_18-5_27'| '1000UF' | '80V'         | '20%'       | 'IO'       | 'CAP ELEC DIP 1000UF 80V(+-20%,18*25)CSA'              | 'DIP'          | ''          | ''            | '20230531'
 '47UF'   | '20V'   | '20%'       | 'SMLF'      | 'SPCAP'    | 'CH647BM8803'(!)             = ''              | ''                 | 'CH647BM8803'                |'TAJ_SX'| '47UF'   | '20V'         | '20%'       | 'DISCRETE' | 'CAP CHIP 47U 20V(20%,105C,SPCAP,7343)MUR'             | 'SMT'          | ''          | ''            | '20230606'
 '47UF'   | '20V'   | '20%'       | 'SMLF'      | 'EMPTY'    | 'CH647BM8803'(!)             = ''              | ''                 | 'CH647BM8803'                |'TAJ_SX'| '47UF'   | '20V'         | '20%'       | 'IO'       | 'CAP CHIP 47U 20V(20%,105C,SPCAP,7343)MUR'             | 'SMT'          | ''          | ''            | '20230606'
 '47UF'   | '80V'   | '20%'       | 'SMLF'      | 'OSCON'    | 'CC6470EMZ02SEL1'(!)         = ''              | ''                 | 'CC6470EMZ02SEL1'            |'EC181_394_496SXA'| '47UF'   | '80V'         | '20%'       | 'DISCRETE' | 'CAPOSCON SMD 47U 80V(20%,10*12.6)MATSELA'             | 'SMT'          | ''          | ''            | '20230629'
 '47UF'   | '80V'   | '20%'       | 'SMLF'      | 'EMPTY'    | 'CC6470EMZ02SEL1'(!)         = ''              | ''                 | 'CC6470EMZ02SEL1'            |'EC181_394_496SXA'| '47UF'   | '80V'         | '20%'       | 'IO'       | 'CAPOSCON SMD 47U 80V(20%,10*12.6)MATSELA'             | 'SMT'          | ''          | ''            | '20230629'
 '100UF'  | '16V'   | '20%'       | 'SMLF'      | 'OSCON'    | 'CC71003MZ28SEL1'(!)         = ''              | ''                 | 'CC71003MZ28SEL1'            |'EC83_248_232S'| '100UF'  | '16V'         | '20%'       | 'DISCRETE' | 'CAPOSCONSMD 100U 16V(20%,6.3*5.9)MATSELA'             | 'SMT'          | ''          | ''            | '20230629'
 '100UF'  | '16V'   | '20%'       | 'SMLF'      | 'EMPTY'    | 'CC71003MZ28SEL1'(!)         = ''              | ''                 | 'CC71003MZ28SEL1'            |'EC83_248_232S'| '100UF'  | '16V'         | '20%'       | 'IO'       | 'CAPOSCONSMD 100U 16V(20%,6.3*5.9)MATSELA'             | 'SMT'          | ''          | ''            | '20230629'
 '220UF'  | '6.3V'  | '20%'       | 'SMLF'      | 'ALUM'     | 'CC72201MZ28SEL1'(!)         = ''              | ''                 | 'CC72201MZ28SEL1'            |'EC56_197_229SXA'| '220UF'  | '6.3V'        | '20%'       | 'DISCRETE' | 'CAPOSSMD220U6.3V(20%,ESR12,5*5.8)NPNSELA'             | 'SMT'          | ''          | ''            | '20230629'
 '220UF'  | '6.3V'  | '20%'       | 'SMLF'      | 'EMPTY'    | 'CC72201MZ28SEL1'(!)         = ''              | ''                 | 'CC72201MZ28SEL1'            |'EC56_197_229SXA'| '220UF'  | '6.3V'        | '20%'       | 'IO'       | 'CAPOSSMD220U6.3V(20%,ESR12,5*5.8)NPNSELA'             | 'SMT'          | ''          | ''            | '20230629'
 '270UF'  | '16V'   | '20%'       | 'SMLF'      | 'OSCON'    | 'CC72703MZ07SEL1'(!)         = ''              | ''                 | 'CC72703MZ07SEL1'            |'EC83_248_390S'| '270UF'  | '16V'         | '20%'       | 'DISCRETE' | 'CAPOSCONSMD 270U 16V(20%,6.3*9.9)MATSELA'             | 'SMT'          | ''          | ''            | '20230629'
 '270UF'  | '16V'   | '20%'       | 'SMLF'      | 'EMPTY'    | 'CC72703MZ07SEL1'(!)         = ''              | ''                 | 'CC72703MZ07SEL1'            |'EC83_248_390S'| '270UF'  | '16V'         | '20%'       | 'IO'       | 'CAPOSCONSMD 270U 16V(20%,6.3*9.9)MATSELA'             | 'SMT'          | ''          | ''            | '20230629'
 '390UF'  | '2.5V'  | '20%'       | 'SMLF'      | 'ALUM'     | 'CC7390JMZ13SEL1'(!)         = ''              | ''                 | 'CC7390JMZ13SEL1'            |'EC56_197_229SXA'| '390UF'  | '2.5V'        | '20%'       | 'DISCRETE' | 'CAPOSSMD390U2.5V(20%,ESR10,5*5.8)NPNSELA'             | 'SMT'          | ''          | ''            | '20230629'
 '390UF'  | '2.5V'  | '20%'       | 'SMLF'      | 'EMPTY'    | 'CC7390JMZ13SEL1'(!)         = ''              | ''                 | 'CC7390JMZ13SEL1'            |'EC56_197_229SXA'| '390UF'  | '2.5V'        | '20%'       | 'IO'       | 'CAPOSSMD390U2.5V(20%,ESR10,5*5.8)NPNSELA'             | 'SMT'          | ''          | ''            | '20230629'
 '330UF'  | '2.5V'  | '+10/-35%'  | 'SMLF'      | 'SPCAP'    | 'CH733LY8805'(!)             = ''              | ''                 | 'CH733LY8805'                |'TAJ_S'| '330UF'  | '2.5V'        | '+10/-35%'  | 'DISCRETE' | 'CAPCHIP 330U 2.5V(10/-35%,SPCAP,7343)APQ'             | 'SMT'          | ''          | ''            | '20230630'
 '330UF'  | '2.5V'  | '+10/-35%'  | 'SMLF'      | 'EMPTY'    | 'CH733LY8805'(!)             = ''              | ''                 | 'CH733LY8805'                |'TAJ_S'| '330UF'  | '2.5V'        | '+10/-35%'  | 'IO'       | 'CAPCHIP 330U 2.5V(10/-35%,SPCAP,7343)APQ'             | 'SMT'          | ''          | ''            | '20230630'
 '220UF'  | '6.3V'  | '20%'       | 'SMLF'      | 'ALUM'     | 'CC72201MZ27SEL1'(!)         = ''              | ''                 | 'CC72201MZ27SEL1'            |'EC56_197_233S'| '220UF'  | '6.3V'        | '20%'       | 'DISCRETE' | 'CAPOSSMD220U6.3V(20%,ESR15,5*5.8)MATSELA'             | 'SMT'          | ''          | ''            | '20160122'
 '220UF'  | '6.3V'  | '20%'       | 'SMLF'      | 'EMPTY'    | 'CC72201MZ27SEL1'(!)         = ''              | ''                 | 'CC72201MZ27SEL1'            |'EC56_197_233S'| '220UF'  | '6.3V'        | '20%'       | 'IO'       | 'CAPOSSMD220U6.3V(20%,ESR15,5*5.8)MATSELA'             | 'SMT'          | ''          | ''            | '20160122'
 '100UF'  | '20V'   | '20%'       | 'SMLF'      | 'POSCAP'   | 'CH710BMI803SEL1'(!)         = ''              | ''                 | 'CH710BMI803SEL1'            |'TAJ_D3L'| '100UF'  | '20V'         | '20%'       | 'DISCRETE' | 'CAP100U20V(20%,POSCAP,ESR55,7343)MATSELA'             | 'SMT'          | ''          | ''            | '20230713'
 '100UF'  | '20V'   | '20%'       | 'SMLF'      | 'EMPTY'    | 'CH710BMI803SEL1'(!)         = ''              | ''                 | 'CH710BMI803SEL1'            |'TAJ_D3L'| '100UF'  | '20V'         | '20%'       | 'IO'       | 'CAP100U20V(20%,POSCAP,ESR55,7343)MATSELA'             | 'SMT'          | ''          | ''            | '20230713'
 '220UF'  | '10V'   | '20%'       | 'SMLF'      | 'POSCAP'   | 'CH7222MI801SEL1'(!)         = ''              | ''                 | 'CH7222MI801SEL1'            |'TAJ_D3L'| '220UF'  | '10V'         | '20%'       | 'DISCRETE' | 'CAPCHIP 220U 10V(20%,POSCAP,7343)MATSELA'             | 'SMT'          | ''          | ''            | '20230713'
 '220UF'  | '10V'   | '20%'       | 'SMLF'      | 'EMPTY'    | 'CH7222MI801SEL1'(!)         = ''              | ''                 | 'CH7222MI801SEL1'            |'TAJ_D3L'| '220UF'  | '10V'         | '20%'       | 'IO'       | 'CAPCHIP 220U 10V(20%,POSCAP,7343)MATSELA'             | 'SMT'          | ''          | ''            | '20230713'
 '330UF'  | '2V'    | '+10-35%'   | 'SMLF'      | 'SPCAP'    | 'CH733RY8807SEL1'(!)         = ''              | ''                 | 'CH733RY8807SEL1'            |'TAJ_DXC'| '330UF'  | '2V'          | '+10-35%'   | 'DISCRETE' | 'CAPCHIP330U2V(10-35%,SPCAP,7343)MATSELA'              | 'SMT'          | ''          | ''            | '20230713'
 '330UF'  | '2V'    | '+10-35%'   | 'SMLF'      | 'EMPTY'    | 'CH733RY8807SEL1'(!)         = ''              | ''                 | 'CH733RY8807SEL1'            |'TAJ_DXC'| '330UF'  | '2V'          | '+10-35%'   | 'IO'       | 'CAPCHIP330U2V(10-35%,SPCAP,7343)MATSELA'              | 'SMT'          | ''          | ''            | '20230713'
 '470UF'  | '2.5V'  | '20%'       | 'SMLF'      | 'SPCAP'    | 'CH747LM8818SEL1'(!)         = ''              | ''                 | 'CH747LM8818SEL1'            |'TAJ_DXC'| '470UF'  | '2.5V'        | '20%'       | 'DISCRETE' | 'CAPCHIP 470U 2.5V(20%,7343,SPCAP)MATSELA'             | 'SMT'          | ''          | ''            | '20230713'
 '470UF'  | '2.5V'  | '20%'       | 'SMLF'      | 'EMPTY'    | 'CH747LM8818SEL1'(!)         = ''              | ''                 | 'CH747LM8818SEL1'            |'TAJ_DXC'| '470UF'  | '2.5V'        | '20%'       | 'IO'       | 'CAPCHIP 470U 2.5V(20%,7343,SPCAP)MATSELA'             | 'SMT'          | ''          | ''            | '20230713'
 '470UF'  | '2.5V'  | '20%'       | 'SMLF'      | 'SPCAP'    | 'CH747LM8825SEL1'(!)         = ''              | ''                 | 'CH747LM8825SEL1'            |'TAJ_SX'| '470UF'  | '2.5V'        | '20%'       | 'DISCRETE' | 'CAPCHIP 470U 2.5V(20%,SP,7343)MATSELA'                | 'SMT'          | ''          | ''            | '20230713'
 '470UF'  | '2.5V'  | '20%'       | 'SMLF'      | 'EMPTY'    | 'CH747LM8825SEL1'(!)         = ''              | ''                 | 'CH747LM8825SEL1'            |'TAJ_SX'| '470UF'  | '2.5V'        | '20%'       | 'IO'       | 'CAPCHIP 470U 2.5V(20%,SP,7343)MATSELA'                | 'SMT'          | ''          | ''            | '20230713'
 '470UF'  | '2.5V'  | '20%'       | 'SMLF'      | 'SPCAP'    | 'CH747LM8829'(!)             = ''               | ''               | 'CH747LM8829'                |'TAJ_S'| '470UF'  | '2.5V'        | '20%'       | 'DISCRETE' | 'CAP CHIP 470UF 2.5V(20%,SPCAP,7343)APQ'               | 'SMT'          | ''          | ''            | '20230809'
 '470UF'  | '2.5V'  | '20%'       | 'SMLF'      | 'EMPTY'    | 'CH747LM8829'(!)             = ''               | ''               | 'CH747LM8829'                |'TAJ_S'| '470UF'  | '2.5V'        | '20%'       | 'IO'       | 'CAP CHIP 470UF 2.5V(20%,SPCAP,7343)APQ'               | 'SMT'          | ''          | ''            | '20230809'

END_PART

END.

